FILE_TYPE = MACRO_DRAWING;
SET COLOR_WIRE YELLOW;
SET COLOR_PROP MONO;
SET COLOR_DOT WHITE;
SET COLOR_ARC YELLOW;
SET COLOR_BODY GREEN;
SET COLOR_NOTE MONO;
SET PROP_DISPLAY VALUE;
SET PAGE_NUMBER P244;
FORCEADD TAP..7
(-5925 1475);
FORCEPROP 3 LASTPIN (-5925 1525) SIG_NAME P3E_CPU0_PE1_PCH_CON_TXP<15>
J 0
(-5915 1535);
DISPLAY 0.659574 (-5915 1535);
PAINT MONO (-5915 1535);
DISPLAY INVISIBLE (-5915 1535);
FORCEPROP 1 LASTPIN (-5925 1525) BN 15
R 1
J 0
(-5932 1473);
DISPLAY 0.680851 (-5932 1473);
PAINT GREEN (-5932 1473);
FORCEPROP 1 LAST HDL_TAP TRUE
J 0
(-5605 1345);
DISPLAY 2.276596 (-5605 1345);
PAINT GREEN (-5605 1345);
DISPLAY INVISIBLE (-5605 1345);
FORCEPROP 1 LAST BODY_TYPE PLUMBING
J 0
(-5875 1475);
DISPLAY 2.276596 (-5875 1475);
PAINT GREEN (-5875 1475);
DISPLAY INVISIBLE (-5875 1475);
FORCEPROP 2 LAST CDS_LIB mstr_standard
J 0
(-5925 1475);
PAINT MONO (-5925 1475);
DISPLAY INVISIBLE (-5925 1475);
FORCEPROP 1 LAST PATH I1
J 0
(-5927 1475);
DISPLAY 0.872340 (-5927 1475);
PAINT GREEN (-5927 1475);
DISPLAY INVISIBLE (-5927 1475);
FORCEADD OFFPAGE..1
(-6200 3625);
FORCEPROP 2 LAST $XR0 30 
J 0
(-6421 3625);
DISPLAY 0.638298 (-6421 3625);
PAINT MONO (-6421 3625);
FORCEPROP 2 LAST $XR1 105 
J 0
(-6541 3625);
DISPLAY 0.638298 (-6541 3625);
PAINT MONO (-6541 3625);
FORCEPROP 1 LAST COMMENT_BODY TRUE
J 0
(-6080 3525);
DISPLAY 2.276596 (-6080 3525);
PAINT GREEN (-6080 3525);
DISPLAY INVISIBLE (-6080 3525);
FORCEPROP 1 LAST OFFPAGE TRUE
J 0
(-5880 3495);
PAINT GREEN (-5880 3495);
DISPLAY INVISIBLE (-5880 3495);
FORCEPROP 2 LAST CDS_LIB mstr_standard
J 0
(-6200 3625);
PAINT MONO (-6200 3625);
DISPLAY INVISIBLE (-6200 3625);
FORCEPROP 2 LAST PATH I10
J 0
(-6400 3675);
DISPLAY 1.021277 (-6400 3675);
PAINT ORANGE (-6400 3675);
DISPLAY INVISIBLE (-6400 3675);
FORCEADD TAP..3
(-2500 3575);
FORCEPROP 3 LASTPIN (-2500 3525) SIG_NAME P3E_CPU0_PE1_PCH_RXN<10>
J 0
(-2490 3535);
DISPLAY 0.659574 (-2490 3535);
PAINT MONO (-2490 3535);
DISPLAY INVISIBLE (-2490 3535);
FORCEPROP 1 LASTPIN (-2500 3525) BN 10
R 1
J 0
(-2507 3513);
DISPLAY 0.680851 (-2507 3513);
PAINT GREEN (-2507 3513);
FORCEPROP 1 LAST HDL_TAP TRUE
J 0
(-2180 3445);
DISPLAY 2.276596 (-2180 3445);
PAINT GREEN (-2180 3445);
DISPLAY INVISIBLE (-2180 3445);
FORCEPROP 1 LAST BODY_TYPE PLUMBING
J 0
(-2450 3525);
DISPLAY 2.276596 (-2450 3525);
PAINT GREEN (-2450 3525);
DISPLAY INVISIBLE (-2450 3525);
FORCEPROP 2 LAST CDS_LIB mstr_standard
J 0
(-2500 3575);
PAINT MONO (-2500 3575);
DISPLAY INVISIBLE (-2500 3575);
FORCEPROP 1 LAST PATH I100
J 0
(-2502 3575);
DISPLAY 0.872340 (-2502 3575);
PAINT GREEN (-2502 3575);
DISPLAY INVISIBLE (-2502 3575);
FORCEADD TAP..3
(-2300 3575);
FORCEPROP 3 LASTPIN (-2300 3525) SIG_NAME P3E_CPU0_PE1_PCH_RXN<9>
J 0
(-2290 3535);
DISPLAY 0.659574 (-2290 3535);
PAINT MONO (-2290 3535);
DISPLAY INVISIBLE (-2290 3535);
FORCEPROP 1 LASTPIN (-2300 3525) BN 9
R 1
J 0
(-2307 3513);
DISPLAY 0.680851 (-2307 3513);
PAINT GREEN (-2307 3513);
FORCEPROP 1 LAST HDL_TAP TRUE
J 0
(-1980 3445);
DISPLAY 2.276596 (-1980 3445);
PAINT GREEN (-1980 3445);
DISPLAY INVISIBLE (-1980 3445);
FORCEPROP 1 LAST BODY_TYPE PLUMBING
J 0
(-2250 3525);
DISPLAY 2.276596 (-2250 3525);
PAINT GREEN (-2250 3525);
DISPLAY INVISIBLE (-2250 3525);
FORCEPROP 2 LAST CDS_LIB mstr_standard
J 0
(-2300 3575);
PAINT MONO (-2300 3575);
DISPLAY INVISIBLE (-2300 3575);
FORCEPROP 1 LAST PATH I101
J 0
(-2302 3575);
DISPLAY 0.872340 (-2302 3575);
PAINT GREEN (-2302 3575);
DISPLAY INVISIBLE (-2302 3575);
FORCEADD TAP..3
(-2100 3575);
FORCEPROP 3 LASTPIN (-2100 3525) SIG_NAME P3E_CPU0_PE1_PCH_RXN<8>
J 0
(-2090 3535);
DISPLAY 0.659574 (-2090 3535);
PAINT MONO (-2090 3535);
DISPLAY INVISIBLE (-2090 3535);
FORCEPROP 1 LASTPIN (-2100 3525) BN 8
R 1
J 0
(-2107 3513);
DISPLAY 0.680851 (-2107 3513);
PAINT GREEN (-2107 3513);
FORCEPROP 1 LAST HDL_TAP TRUE
J 0
(-1780 3445);
DISPLAY 2.276596 (-1780 3445);
PAINT GREEN (-1780 3445);
DISPLAY INVISIBLE (-1780 3445);
FORCEPROP 1 LAST BODY_TYPE PLUMBING
J 0
(-2050 3525);
DISPLAY 2.276596 (-2050 3525);
PAINT GREEN (-2050 3525);
DISPLAY INVISIBLE (-2050 3525);
FORCEPROP 2 LAST CDS_LIB mstr_standard
J 0
(-2100 3575);
PAINT MONO (-2100 3575);
DISPLAY INVISIBLE (-2100 3575);
FORCEPROP 1 LAST PATH I102
J 0
(-2102 3575);
DISPLAY 0.872340 (-2102 3575);
PAINT GREEN (-2102 3575);
DISPLAY INVISIBLE (-2102 3575);
FORCEADD RES..2
(-2025 2025);
FORCEPROP 1 LAST PART_NUMBER G21497-005
J 0
(-1985 1900);
DISPLAY 0.617021 (-1985 1900);
PAINT BLUE (-1985 1900);
FORCEPROP 1 LAST MATERIAL CHIP
J 0
(-1985 1950);
DISPLAY 0.617021 (-1985 1950);
PAINT SKYBLUE (-1985 1950);
FORCEPROP 1 LAST WATTAGE 1/16W
J 0
(-1985 2000);
DISPLAY 0.617021 (-1985 2000);
PAINT SKYBLUE (-1985 2000);
FORCEPROP 1 LAST VALUE 0.0
J 0
(-1980 2100);
DISPLAY 0.617021 (-1980 2100);
PAINT SKYBLUE (-1980 2100);
FORCEPROP 1 LAST TOLERANCE 5%
J 0
(-1980 2050);
DISPLAY 0.617021 (-1980 2050);
PAINT SKYBLUE (-1980 2050);
FORCEPROP 1 LAST PACK_TYPE 0402
J 0
(-1985 1850);
DISPLAY 0.617021 (-1985 1850);
PAINT SKYBLUE (-1985 1850);
FORCEPROP 1 LAST $LOCATION R785
J 0
(-1980 2150);
DISPLAY 0.617021 (-1980 2150);
PAINT AQUA (-1980 2150);
FORCEPROP 2 LAST ROOM PCIE_STEERING
J 0
(-1975 2200);
PAINT MONO (-1975 2200);
DISPLAY INVISIBLE (-1975 2200);
FORCEPROP 2 LAST CDS_LIB mstr_discrete
J 0
(-2025 2025);
PAINT MONO (-2025 2025);
DISPLAY INVISIBLE (-2025 2025);
FORCEPROP 1 LASTPIN (-2025 1925) $PN 2
J 0
(-2020 1935);
DISPLAY 0.787234 (-2020 1935);
PAINT ORANGE (-2020 1935);
DISPLAY INVISIBLE (-2020 1935);
FORCEPROP 1 LASTPIN (-2025 2125) $PN 1
J 0
(-2020 2087);
DISPLAY 0.787234 (-2020 2087);
PAINT ORANGE (-2020 2087);
DISPLAY INVISIBLE (-2020 2087);
FORCEPROP 0 LAST CDS_LOCATION R785
J 0
(-1975 2200);
PAINT MONO (-1975 2200);
DISPLAY INVISIBLE (-1975 2200);
FORCEPROP 0 LAST $SEC 1
J 0
(-1975 2200);
PAINT MONO (-1975 2200);
DISPLAY INVISIBLE (-1975 2200);
FORCEPROP 0 LAST CDS_SEC 1
J 0
(-1975 2200);
PAINT MONO (-1975 2200);
DISPLAY INVISIBLE (-1975 2200);
FORCEPROP 1 LAST PATH I103
J 0
(-1975 2200);
DISPLAY 0.978723 (-1975 2200);
PAINT WHITE (-1975 2200);
DISPLAY INVISIBLE (-1975 2200);
FORCEADD OFFPAGE..2
(-1800 2725);
FORCEPROP 2 LAST $XR0 108 
J 0
(-1611 2725);
DISPLAY 0.638298 (-1611 2725);
PAINT MONO (-1611 2725);
FORCEPROP 2 LAST $XR1 ?
J 0
(-1491 2725);
DISPLAY 0.638298 (-1491 2725);
PAINT MONO (-1491 2725);
FORCEPROP 2 LAST $XRERR ?
J 0
(-1611 2725);
DISPLAY 0.638298 (-1611 2725);
PAINT MONO (-1611 2725);
DISPLAY INVISIBLE (-1611 2725);
FORCEPROP 2 LAST $XRERR ?
J 0
(-1611 2725);
DISPLAY 0.638298 (-1611 2725);
PAINT MONO (-1611 2725);
DISPLAY INVISIBLE (-1611 2725);
FORCEPROP 2 LAST $XRERR ?
J 0
(-1611 2725);
DISPLAY 0.638298 (-1611 2725);
PAINT MONO (-1611 2725);
DISPLAY INVISIBLE (-1611 2725);
FORCEPROP 1 LAST COMMENT_BODY TRUE
J 0
(-1845 2630);
DISPLAY 0.872340 (-1845 2630);
PAINT GREEN (-1845 2630);
DISPLAY INVISIBLE (-1845 2630);
FORCEPROP 1 LAST OFFPAGE TRUE
J 0
(-1475 2600);
DISPLAY 0.872340 (-1475 2600);
PAINT GREEN (-1475 2600);
DISPLAY INVISIBLE (-1475 2600);
FORCEPROP 2 LAST CDS_LIB mstr_standard
J 0
(-1800 2725);
PAINT MONO (-1800 2725);
DISPLAY INVISIBLE (-1800 2725);
FORCEPROP 2 LAST PATH I104
J 0
(-1475 2775);
DISPLAY 1.021277 (-1475 2775);
PAINT ORANGE (-1475 2775);
DISPLAY INVISIBLE (-1475 2775);
FORCEADD TAP..3
(-5925 2275);
FORCEPROP 3 LASTPIN (-5925 2225) SIG_NAME P3E_CPU0_PE1_PCH_TXP<15>
J 0
(-5915 2235);
DISPLAY 0.659574 (-5915 2235);
PAINT MONO (-5915 2235);
DISPLAY INVISIBLE (-5915 2235);
FORCEPROP 1 LASTPIN (-5925 2225) BN 15
R 1
J 0
(-5932 2213);
DISPLAY 0.680851 (-5932 2213);
PAINT GREEN (-5932 2213);
FORCEPROP 1 LAST HDL_TAP TRUE
J 0
(-5605 2145);
DISPLAY 2.276596 (-5605 2145);
PAINT GREEN (-5605 2145);
DISPLAY INVISIBLE (-5605 2145);
FORCEPROP 1 LAST BODY_TYPE PLUMBING
J 0
(-5875 2225);
DISPLAY 2.276596 (-5875 2225);
PAINT GREEN (-5875 2225);
DISPLAY INVISIBLE (-5875 2225);
FORCEPROP 2 LAST CDS_LIB mstr_standard
J 0
(-5925 2275);
PAINT MONO (-5925 2275);
DISPLAY INVISIBLE (-5925 2275);
FORCEPROP 1 LAST PATH I11
J 0
(-5927 2275);
DISPLAY 0.872340 (-5927 2275);
PAINT GREEN (-5927 2275);
DISPLAY INVISIBLE (-5927 2275);
FORCEADD CAP..1
R 2
(-5725 2025);
FORCEPROP 1 LAST TOLERANCE 10%
J 2
(-5775 1975);
DISPLAY 0.617021 (-5775 1975);
PAINT SKYBLUE (-5775 1975);
FORCEPROP 1 LAST VOLTAGE 16V
J 2
(-5775 2025);
DISPLAY 0.617021 (-5775 2025);
PAINT SKYBLUE (-5775 2025);
FORCEPROP 1 LAST VALUE 0.22UF
J 2
(-5775 2075);
DISPLAY 0.617021 (-5775 2075);
PAINT SKYBLUE (-5775 2075);
FORCEPROP 1 LAST PACK_TYPE 0402
J 2
(-5775 1825);
DISPLAY 0.617021 (-5775 1825);
PAINT SKYBLUE (-5775 1825);
FORCEPROP 1 LAST MATERIAL X7R
J 2
(-5775 1925);
DISPLAY 0.617021 (-5775 1925);
PAINT SKYBLUE (-5775 1925);
FORCEPROP 1 LAST $LOCATION C827
J 2
(-5775 2125);
DISPLAY 0.617021 (-5775 2125);
PAINT AQUA (-5775 2125);
FORCEPROP 1 LAST PART_NUMBER A36096-155
J 2
(-5775 1875);
DISPLAY 0.617021 (-5775 1875);
PAINT BLUE (-5775 1875);
FORCEPROP 2 LAST ROOM OCP_STEERING
J 2
(-5725 2025);
PAINT MONO (-5725 2025);
DISPLAY INVISIBLE (-5725 2025);
FORCEPROP 2 LAST CDS_LIB mstr_discrete
J 0
(-5725 2025);
PAINT MONO (-5725 2025);
DISPLAY INVISIBLE (-5725 2025);
FORCEPROP 1 LASTPIN (-5725 1925) $PN 2
J 2
(-5735 1905);
DISPLAY 0.787234 (-5735 1905);
PAINT ORANGE (-5735 1905);
DISPLAY INVISIBLE (-5735 1905);
FORCEPROP 1 LASTPIN (-5725 2125) $PN 1
J 2
(-5735 2105);
DISPLAY 0.787234 (-5735 2105);
PAINT ORANGE (-5735 2105);
DISPLAY INVISIBLE (-5735 2105);
FORCEPROP 2 LAST CDS_LOCATION C827
J 2
(-5775 2125);
DISPLAY 0.617021 (-5775 2125);
PAINT AQUA (-5775 2125);
DISPLAY INVISIBLE (-5775 2125);
FORCEPROP 0 LAST $SEC 1
J 0
(-5775 2175);
PAINT MONO (-5775 2175);
DISPLAY INVISIBLE (-5775 2175);
FORCEPROP 0 LAST CDS_SEC 1
J 0
(-5775 2175);
PAINT MONO (-5775 2175);
DISPLAY INVISIBLE (-5775 2175);
FORCEPROP 1 LAST PATH I12
J 2
(-5775 2175);
DISPLAY 0.978723 (-5775 2175);
PAINT WHITE (-5775 2175);
DISPLAY INVISIBLE (-5775 2175);
FORCEADD TAP..3
(-5725 2275);
FORCEPROP 3 LASTPIN (-5725 2225) SIG_NAME P3E_CPU0_PE1_PCH_TXP<14>
J 0
(-5715 2235);
DISPLAY 0.659574 (-5715 2235);
PAINT MONO (-5715 2235);
DISPLAY INVISIBLE (-5715 2235);
FORCEPROP 1 LASTPIN (-5725 2225) BN 14
R 1
J 0
(-5732 2213);
DISPLAY 0.680851 (-5732 2213);
PAINT GREEN (-5732 2213);
FORCEPROP 1 LAST HDL_TAP TRUE
J 0
(-5405 2145);
DISPLAY 2.276596 (-5405 2145);
PAINT GREEN (-5405 2145);
DISPLAY INVISIBLE (-5405 2145);
FORCEPROP 1 LAST BODY_TYPE PLUMBING
J 0
(-5675 2225);
DISPLAY 2.276596 (-5675 2225);
PAINT GREEN (-5675 2225);
DISPLAY INVISIBLE (-5675 2225);
FORCEPROP 2 LAST CDS_LIB mstr_standard
J 0
(-5725 2275);
PAINT MONO (-5725 2275);
DISPLAY INVISIBLE (-5725 2275);
FORCEPROP 1 LAST PATH I13
J 0
(-5727 2275);
DISPLAY 0.872340 (-5727 2275);
PAINT GREEN (-5727 2275);
DISPLAY INVISIBLE (-5727 2275);
FORCEADD TAP..7
(-6025 2775);
FORCEPROP 3 LASTPIN (-6025 2825) SIG_NAME P3E_CPU0_PE1_PCH_CON_TXN<15>
J 0
(-6015 2835);
DISPLAY 0.659574 (-6015 2835);
PAINT MONO (-6015 2835);
DISPLAY INVISIBLE (-6015 2835);
FORCEPROP 1 LASTPIN (-6025 2825) BN 15
R 1
J 0
(-6032 2773);
DISPLAY 0.680851 (-6032 2773);
PAINT GREEN (-6032 2773);
FORCEPROP 1 LAST HDL_TAP TRUE
J 0
(-5705 2645);
DISPLAY 2.276596 (-5705 2645);
PAINT GREEN (-5705 2645);
DISPLAY INVISIBLE (-5705 2645);
FORCEPROP 1 LAST BODY_TYPE PLUMBING
J 0
(-5975 2775);
DISPLAY 2.276596 (-5975 2775);
PAINT GREEN (-5975 2775);
DISPLAY INVISIBLE (-5975 2775);
FORCEPROP 2 LAST CDS_LIB mstr_standard
J 0
(-6025 2775);
PAINT MONO (-6025 2775);
DISPLAY INVISIBLE (-6025 2775);
FORCEPROP 1 LAST PATH I14
J 0
(-6027 2775);
DISPLAY 0.872340 (-6027 2775);
PAINT GREEN (-6027 2775);
DISPLAY INVISIBLE (-6027 2775);
FORCEADD TAP..7
(-5825 2775);
FORCEPROP 3 LASTPIN (-5825 2825) SIG_NAME P3E_CPU0_PE1_PCH_CON_TXN<14>
J 0
(-5815 2835);
DISPLAY 0.659574 (-5815 2835);
PAINT MONO (-5815 2835);
DISPLAY INVISIBLE (-5815 2835);
FORCEPROP 1 LASTPIN (-5825 2825) BN 14
R 1
J 0
(-5832 2773);
DISPLAY 0.680851 (-5832 2773);
PAINT GREEN (-5832 2773);
FORCEPROP 1 LAST HDL_TAP TRUE
J 0
(-5505 2645);
DISPLAY 2.276596 (-5505 2645);
PAINT GREEN (-5505 2645);
DISPLAY INVISIBLE (-5505 2645);
FORCEPROP 1 LAST BODY_TYPE PLUMBING
J 0
(-5775 2775);
DISPLAY 2.276596 (-5775 2775);
PAINT GREEN (-5775 2775);
DISPLAY INVISIBLE (-5775 2775);
FORCEPROP 2 LAST CDS_LIB mstr_standard
J 0
(-5825 2775);
PAINT MONO (-5825 2775);
DISPLAY INVISIBLE (-5825 2775);
FORCEPROP 1 LAST PATH I15
J 0
(-5827 2775);
DISPLAY 0.872340 (-5827 2775);
PAINT GREEN (-5827 2775);
DISPLAY INVISIBLE (-5827 2775);
FORCEADD TAP..3
(-5525 2275);
FORCEPROP 3 LASTPIN (-5525 2225) SIG_NAME P3E_CPU0_PE1_PCH_TXP<13>
J 0
(-5515 2235);
DISPLAY 0.659574 (-5515 2235);
PAINT MONO (-5515 2235);
DISPLAY INVISIBLE (-5515 2235);
FORCEPROP 1 LASTPIN (-5525 2225) BN 13
R 1
J 0
(-5532 2213);
DISPLAY 0.680851 (-5532 2213);
PAINT GREEN (-5532 2213);
FORCEPROP 1 LAST HDL_TAP TRUE
J 0
(-5205 2145);
DISPLAY 2.276596 (-5205 2145);
PAINT GREEN (-5205 2145);
DISPLAY INVISIBLE (-5205 2145);
FORCEPROP 1 LAST BODY_TYPE PLUMBING
J 0
(-5475 2225);
DISPLAY 2.276596 (-5475 2225);
PAINT GREEN (-5475 2225);
DISPLAY INVISIBLE (-5475 2225);
FORCEPROP 2 LAST CDS_LIB mstr_standard
J 0
(-5525 2275);
PAINT MONO (-5525 2275);
DISPLAY INVISIBLE (-5525 2275);
FORCEPROP 1 LAST PATH I16
J 0
(-5527 2275);
DISPLAY 0.872340 (-5527 2275);
PAINT GREEN (-5527 2275);
DISPLAY INVISIBLE (-5527 2275);
FORCEADD CAP..1
R 2
(-5325 2025);
FORCEPROP 1 LAST PACK_TYPE 0402
J 2
(-5375 1825);
DISPLAY 0.617021 (-5375 1825);
PAINT SKYBLUE (-5375 1825);
FORCEPROP 1 LAST PART_NUMBER A36096-155
J 2
(-5375 1875);
DISPLAY 0.617021 (-5375 1875);
PAINT BLUE (-5375 1875);
FORCEPROP 1 LAST TOLERANCE 10%
J 2
(-5375 1975);
DISPLAY 0.617021 (-5375 1975);
PAINT SKYBLUE (-5375 1975);
FORCEPROP 1 LAST $LOCATION C841
J 2
(-5375 2125);
DISPLAY 0.617021 (-5375 2125);
PAINT AQUA (-5375 2125);
FORCEPROP 1 LAST VALUE 0.22UF
J 2
(-5375 2075);
DISPLAY 0.617021 (-5375 2075);
PAINT SKYBLUE (-5375 2075);
FORCEPROP 1 LAST VOLTAGE 16V
J 2
(-5375 2025);
DISPLAY 0.617021 (-5375 2025);
PAINT SKYBLUE (-5375 2025);
FORCEPROP 1 LAST MATERIAL X7R
J 2
(-5375 1925);
DISPLAY 0.617021 (-5375 1925);
PAINT SKYBLUE (-5375 1925);
FORCEPROP 2 LAST ROOM OCP_STEERING
J 2
(-5325 2025);
PAINT MONO (-5325 2025);
DISPLAY INVISIBLE (-5325 2025);
FORCEPROP 2 LAST CDS_LIB mstr_discrete
J 0
(-5325 2025);
PAINT MONO (-5325 2025);
DISPLAY INVISIBLE (-5325 2025);
FORCEPROP 1 LASTPIN (-5325 1925) $PN 2
J 2
(-5335 1905);
DISPLAY 0.787234 (-5335 1905);
PAINT ORANGE (-5335 1905);
DISPLAY INVISIBLE (-5335 1905);
FORCEPROP 1 LASTPIN (-5325 2125) $PN 1
J 2
(-5335 2105);
DISPLAY 0.787234 (-5335 2105);
PAINT ORANGE (-5335 2105);
DISPLAY INVISIBLE (-5335 2105);
FORCEPROP 2 LAST CDS_LOCATION C841
J 2
(-5375 2125);
DISPLAY 0.617021 (-5375 2125);
PAINT AQUA (-5375 2125);
DISPLAY INVISIBLE (-5375 2125);
FORCEPROP 0 LAST $SEC 1
J 0
(-5375 2175);
PAINT MONO (-5375 2175);
DISPLAY INVISIBLE (-5375 2175);
FORCEPROP 0 LAST CDS_SEC 1
J 0
(-5375 2175);
PAINT MONO (-5375 2175);
DISPLAY INVISIBLE (-5375 2175);
FORCEPROP 1 LAST PATH I17
J 2
(-5375 2175);
DISPLAY 0.978723 (-5375 2175);
PAINT WHITE (-5375 2175);
DISPLAY INVISIBLE (-5375 2175);
FORCEADD TAP..3
(-5325 2275);
FORCEPROP 3 LASTPIN (-5325 2225) SIG_NAME P3E_CPU0_PE1_PCH_TXP<12>
J 0
(-5315 2235);
DISPLAY 0.659574 (-5315 2235);
PAINT MONO (-5315 2235);
DISPLAY INVISIBLE (-5315 2235);
FORCEPROP 1 LASTPIN (-5325 2225) BN 12
R 1
J 0
(-5332 2213);
DISPLAY 0.680851 (-5332 2213);
PAINT GREEN (-5332 2213);
FORCEPROP 1 LAST HDL_TAP TRUE
J 0
(-5005 2145);
DISPLAY 2.276596 (-5005 2145);
PAINT GREEN (-5005 2145);
DISPLAY INVISIBLE (-5005 2145);
FORCEPROP 1 LAST BODY_TYPE PLUMBING
J 0
(-5275 2225);
DISPLAY 2.276596 (-5275 2225);
PAINT GREEN (-5275 2225);
DISPLAY INVISIBLE (-5275 2225);
FORCEPROP 2 LAST CDS_LIB mstr_standard
J 0
(-5325 2275);
PAINT MONO (-5325 2275);
DISPLAY INVISIBLE (-5325 2275);
FORCEPROP 1 LAST PATH I18
J 0
(-5327 2275);
DISPLAY 0.872340 (-5327 2275);
PAINT GREEN (-5327 2275);
DISPLAY INVISIBLE (-5327 2275);
FORCEADD TAP..3
(-5125 2275);
FORCEPROP 3 LASTPIN (-5125 2225) SIG_NAME P3E_CPU0_PE1_PCH_TXP<11>
J 0
(-5115 2235);
DISPLAY 0.659574 (-5115 2235);
PAINT MONO (-5115 2235);
DISPLAY INVISIBLE (-5115 2235);
FORCEPROP 1 LASTPIN (-5125 2225) BN 11
R 1
J 0
(-5132 2213);
DISPLAY 0.680851 (-5132 2213);
PAINT GREEN (-5132 2213);
FORCEPROP 1 LAST HDL_TAP TRUE
J 0
(-4805 2145);
DISPLAY 2.276596 (-4805 2145);
PAINT GREEN (-4805 2145);
DISPLAY INVISIBLE (-4805 2145);
FORCEPROP 1 LAST BODY_TYPE PLUMBING
J 0
(-5075 2225);
DISPLAY 2.276596 (-5075 2225);
PAINT GREEN (-5075 2225);
DISPLAY INVISIBLE (-5075 2225);
FORCEPROP 2 LAST CDS_LIB mstr_standard
J 0
(-5125 2275);
PAINT MONO (-5125 2275);
DISPLAY INVISIBLE (-5125 2275);
FORCEPROP 1 LAST PATH I19
J 0
(-5127 2275);
DISPLAY 0.872340 (-5127 2275);
PAINT GREEN (-5127 2275);
DISPLAY INVISIBLE (-5127 2275);
FORCEADD CAP..1
R 2
(-5925 1725);
FORCEPROP 1 LAST VOLTAGE 16V
J 2
(-5975 1725);
DISPLAY 0.617021 (-5975 1725);
PAINT SKYBLUE (-5975 1725);
FORCEPROP 1 LAST $LOCATION C831
J 2
(-5975 1825);
DISPLAY 0.617021 (-5975 1825);
PAINT AQUA (-5975 1825);
FORCEPROP 1 LAST PART_NUMBER A36096-155
J 2
(-5975 1575);
DISPLAY 0.617021 (-5975 1575);
PAINT BLUE (-5975 1575);
FORCEPROP 1 LAST TOLERANCE 10%
J 2
(-5975 1675);
DISPLAY 0.617021 (-5975 1675);
PAINT SKYBLUE (-5975 1675);
FORCEPROP 1 LAST MATERIAL X7R
J 2
(-5975 1625);
DISPLAY 0.617021 (-5975 1625);
PAINT SKYBLUE (-5975 1625);
FORCEPROP 1 LAST PACK_TYPE 0402
J 2
(-5975 1525);
DISPLAY 0.617021 (-5975 1525);
PAINT SKYBLUE (-5975 1525);
FORCEPROP 1 LAST VALUE 0.22UF
J 2
(-5975 1775);
DISPLAY 0.617021 (-5975 1775);
PAINT SKYBLUE (-5975 1775);
FORCEPROP 2 LAST ROOM OCP_STEERING
J 2
(-5925 1725);
PAINT MONO (-5925 1725);
DISPLAY INVISIBLE (-5925 1725);
FORCEPROP 2 LAST CDS_LIB mstr_discrete
J 0
(-5925 1725);
PAINT MONO (-5925 1725);
DISPLAY INVISIBLE (-5925 1725);
FORCEPROP 1 LASTPIN (-5925 1625) $PN 2
J 2
(-5935 1605);
DISPLAY 0.787234 (-5935 1605);
PAINT ORANGE (-5935 1605);
DISPLAY INVISIBLE (-5935 1605);
FORCEPROP 1 LASTPIN (-5925 1825) $PN 1
J 2
(-5935 1805);
DISPLAY 0.787234 (-5935 1805);
PAINT ORANGE (-5935 1805);
DISPLAY INVISIBLE (-5935 1805);
FORCEPROP 2 LAST CDS_LOCATION C831
J 2
(-5975 1825);
DISPLAY 0.617021 (-5975 1825);
PAINT AQUA (-5975 1825);
DISPLAY INVISIBLE (-5975 1825);
FORCEPROP 0 LAST $SEC 1
J 0
(-5975 1875);
PAINT MONO (-5975 1875);
DISPLAY INVISIBLE (-5975 1875);
FORCEPROP 0 LAST CDS_SEC 1
J 0
(-5975 1875);
PAINT MONO (-5975 1875);
DISPLAY INVISIBLE (-5975 1875);
FORCEPROP 1 LAST PATH I2
J 2
(-5975 1875);
DISPLAY 0.978723 (-5975 1875);
PAINT WHITE (-5975 1875);
DISPLAY INVISIBLE (-5975 1875);
FORCEADD TAP..7
(-5625 2775);
FORCEPROP 3 LASTPIN (-5625 2825) SIG_NAME P3E_CPU0_PE1_PCH_CON_TXN<13>
J 0
(-5615 2835);
DISPLAY 0.659574 (-5615 2835);
PAINT MONO (-5615 2835);
DISPLAY INVISIBLE (-5615 2835);
FORCEPROP 1 LASTPIN (-5625 2825) BN 13
R 1
J 0
(-5632 2773);
DISPLAY 0.680851 (-5632 2773);
PAINT GREEN (-5632 2773);
FORCEPROP 1 LAST HDL_TAP TRUE
J 0
(-5305 2645);
DISPLAY 2.276596 (-5305 2645);
PAINT GREEN (-5305 2645);
DISPLAY INVISIBLE (-5305 2645);
FORCEPROP 1 LAST BODY_TYPE PLUMBING
J 0
(-5575 2775);
DISPLAY 2.276596 (-5575 2775);
PAINT GREEN (-5575 2775);
DISPLAY INVISIBLE (-5575 2775);
FORCEPROP 2 LAST CDS_LIB mstr_standard
J 0
(-5625 2775);
PAINT MONO (-5625 2775);
DISPLAY INVISIBLE (-5625 2775);
FORCEPROP 1 LAST PATH I20
J 0
(-5627 2775);
DISPLAY 0.872340 (-5627 2775);
PAINT GREEN (-5627 2775);
DISPLAY INVISIBLE (-5627 2775);
FORCEADD TAP..7
(-5425 2775);
FORCEPROP 3 LASTPIN (-5425 2825) SIG_NAME P3E_CPU0_PE1_PCH_CON_TXN<12>
J 0
(-5415 2835);
DISPLAY 0.659574 (-5415 2835);
PAINT MONO (-5415 2835);
DISPLAY INVISIBLE (-5415 2835);
FORCEPROP 1 LASTPIN (-5425 2825) BN 12
R 1
J 0
(-5432 2773);
DISPLAY 0.680851 (-5432 2773);
PAINT GREEN (-5432 2773);
FORCEPROP 1 LAST HDL_TAP TRUE
J 0
(-5105 2645);
DISPLAY 2.276596 (-5105 2645);
PAINT GREEN (-5105 2645);
DISPLAY INVISIBLE (-5105 2645);
FORCEPROP 1 LAST BODY_TYPE PLUMBING
J 0
(-5375 2775);
DISPLAY 2.276596 (-5375 2775);
PAINT GREEN (-5375 2775);
DISPLAY INVISIBLE (-5375 2775);
FORCEPROP 2 LAST CDS_LIB mstr_standard
J 0
(-5425 2775);
PAINT MONO (-5425 2775);
DISPLAY INVISIBLE (-5425 2775);
FORCEPROP 1 LAST PATH I21
J 0
(-5427 2775);
DISPLAY 0.872340 (-5427 2775);
PAINT GREEN (-5427 2775);
DISPLAY INVISIBLE (-5427 2775);
FORCEADD TAP..7
(-5225 2775);
FORCEPROP 3 LASTPIN (-5225 2825) SIG_NAME P3E_CPU0_PE1_PCH_CON_TXN<11>
J 0
(-5215 2835);
DISPLAY 0.659574 (-5215 2835);
PAINT MONO (-5215 2835);
DISPLAY INVISIBLE (-5215 2835);
FORCEPROP 1 LASTPIN (-5225 2825) BN 11
R 1
J 0
(-5232 2773);
DISPLAY 0.680851 (-5232 2773);
PAINT GREEN (-5232 2773);
FORCEPROP 1 LAST HDL_TAP TRUE
J 0
(-4905 2645);
DISPLAY 2.276596 (-4905 2645);
PAINT GREEN (-4905 2645);
DISPLAY INVISIBLE (-4905 2645);
FORCEPROP 1 LAST BODY_TYPE PLUMBING
J 0
(-5175 2775);
DISPLAY 2.276596 (-5175 2775);
PAINT GREEN (-5175 2775);
DISPLAY INVISIBLE (-5175 2775);
FORCEPROP 2 LAST CDS_LIB mstr_standard
J 0
(-5225 2775);
PAINT MONO (-5225 2775);
DISPLAY INVISIBLE (-5225 2775);
FORCEPROP 1 LAST PATH I22
J 0
(-5227 2775);
DISPLAY 0.872340 (-5227 2775);
PAINT GREEN (-5227 2775);
DISPLAY INVISIBLE (-5227 2775);
FORCEADD CAP..1
R 2
(-6025 3025);
FORCEPROP 1 LAST TOLERANCE 10%
J 2
(-6075 2975);
DISPLAY 0.617021 (-6075 2975);
PAINT SKYBLUE (-6075 2975);
FORCEPROP 1 LAST PART_NUMBER A36096-155
J 2
(-6075 2875);
DISPLAY 0.617021 (-6075 2875);
PAINT BLUE (-6075 2875);
FORCEPROP 1 LAST PACK_TYPE 0402
J 2
(-6075 2825);
DISPLAY 0.617021 (-6075 2825);
PAINT SKYBLUE (-6075 2825);
FORCEPROP 1 LAST VOLTAGE 16V
J 2
(-6075 3025);
DISPLAY 0.617021 (-6075 3025);
PAINT SKYBLUE (-6075 3025);
FORCEPROP 1 LAST MATERIAL X7R
J 2
(-6075 2925);
DISPLAY 0.617021 (-6075 2925);
PAINT SKYBLUE (-6075 2925);
FORCEPROP 1 LAST VALUE 0.22UF
J 2
(-6075 3075);
DISPLAY 0.617021 (-6075 3075);
PAINT SKYBLUE (-6075 3075);
FORCEPROP 1 LAST $LOCATION C830
J 2
(-6075 3125);
DISPLAY 0.617021 (-6075 3125);
PAINT AQUA (-6075 3125);
FORCEPROP 2 LAST CDS_LIB mstr_discrete
J 0
(-6025 3025);
PAINT MONO (-6025 3025);
DISPLAY INVISIBLE (-6025 3025);
FORCEPROP 2 LAST ROOM OCP_STEERING
J 2
(-6025 3025);
PAINT MONO (-6025 3025);
DISPLAY INVISIBLE (-6025 3025);
FORCEPROP 1 LASTPIN (-6025 2925) $PN 2
J 2
(-6035 2905);
DISPLAY 0.787234 (-6035 2905);
PAINT ORANGE (-6035 2905);
DISPLAY INVISIBLE (-6035 2905);
FORCEPROP 1 LASTPIN (-6025 3125) $PN 1
J 2
(-6035 3105);
DISPLAY 0.787234 (-6035 3105);
PAINT ORANGE (-6035 3105);
DISPLAY INVISIBLE (-6035 3105);
FORCEPROP 2 LAST CDS_LOCATION C830
J 2
(-6075 3125);
DISPLAY 0.617021 (-6075 3125);
PAINT AQUA (-6075 3125);
DISPLAY INVISIBLE (-6075 3125);
FORCEPROP 0 LAST $SEC 1
J 0
(-6075 3175);
PAINT MONO (-6075 3175);
DISPLAY INVISIBLE (-6075 3175);
FORCEPROP 0 LAST CDS_SEC 1
J 0
(-6075 3175);
PAINT MONO (-6075 3175);
DISPLAY INVISIBLE (-6075 3175);
FORCEPROP 1 LAST PATH I23
J 2
(-6075 3175);
DISPLAY 0.978723 (-6075 3175);
PAINT WHITE (-6075 3175);
DISPLAY INVISIBLE (-6075 3175);
FORCEADD CAP..1
R 2
(-5825 3325);
FORCEPROP 1 LAST PART_NUMBER A36096-155
J 2
(-5875 3175);
DISPLAY 0.617021 (-5875 3175);
PAINT BLUE (-5875 3175);
FORCEPROP 1 LAST VOLTAGE 16V
J 2
(-5875 3325);
DISPLAY 0.617021 (-5875 3325);
PAINT SKYBLUE (-5875 3325);
FORCEPROP 1 LAST MATERIAL X7R
J 2
(-5875 3225);
DISPLAY 0.617021 (-5875 3225);
PAINT SKYBLUE (-5875 3225);
FORCEPROP 1 LAST PACK_TYPE 0402
J 2
(-5875 3125);
DISPLAY 0.617021 (-5875 3125);
PAINT SKYBLUE (-5875 3125);
FORCEPROP 1 LAST TOLERANCE 10%
J 2
(-5875 3275);
DISPLAY 0.617021 (-5875 3275);
PAINT SKYBLUE (-5875 3275);
FORCEPROP 1 LAST $LOCATION C826
J 2
(-5875 3425);
DISPLAY 0.617021 (-5875 3425);
PAINT AQUA (-5875 3425);
FORCEPROP 1 LAST VALUE 0.22UF
J 2
(-5875 3375);
DISPLAY 0.617021 (-5875 3375);
PAINT SKYBLUE (-5875 3375);
FORCEPROP 2 LAST CDS_LIB mstr_discrete
J 0
(-5825 3325);
PAINT MONO (-5825 3325);
DISPLAY INVISIBLE (-5825 3325);
FORCEPROP 2 LAST ROOM OCP_STEERING
J 2
(-5825 3325);
PAINT MONO (-5825 3325);
DISPLAY INVISIBLE (-5825 3325);
FORCEPROP 1 LASTPIN (-5825 3225) $PN 2
J 2
(-5835 3205);
DISPLAY 0.787234 (-5835 3205);
PAINT ORANGE (-5835 3205);
DISPLAY INVISIBLE (-5835 3205);
FORCEPROP 1 LASTPIN (-5825 3425) $PN 1
J 2
(-5835 3405);
DISPLAY 0.787234 (-5835 3405);
PAINT ORANGE (-5835 3405);
DISPLAY INVISIBLE (-5835 3405);
FORCEPROP 2 LAST CDS_LOCATION C826
J 2
(-5875 3425);
DISPLAY 0.617021 (-5875 3425);
PAINT AQUA (-5875 3425);
DISPLAY INVISIBLE (-5875 3425);
FORCEPROP 0 LAST $SEC 1
J 0
(-5875 3475);
PAINT MONO (-5875 3475);
DISPLAY INVISIBLE (-5875 3475);
FORCEPROP 0 LAST CDS_SEC 1
J 0
(-5875 3475);
PAINT MONO (-5875 3475);
DISPLAY INVISIBLE (-5875 3475);
FORCEPROP 1 LAST PATH I24
J 2
(-5875 3475);
DISPLAY 0.978723 (-5875 3475);
PAINT WHITE (-5875 3475);
DISPLAY INVISIBLE (-5875 3475);
FORCEADD TAP..3
(-6025 3575);
FORCEPROP 3 LASTPIN (-6025 3525) SIG_NAME P3E_CPU0_PE1_PCH_TXN<15>
J 0
(-6015 3535);
DISPLAY 0.659574 (-6015 3535);
PAINT MONO (-6015 3535);
DISPLAY INVISIBLE (-6015 3535);
FORCEPROP 1 LASTPIN (-6025 3525) BN 15
R 1
J 0
(-6032 3513);
DISPLAY 0.680851 (-6032 3513);
PAINT GREEN (-6032 3513);
FORCEPROP 1 LAST HDL_TAP TRUE
J 0
(-5705 3445);
DISPLAY 2.276596 (-5705 3445);
PAINT GREEN (-5705 3445);
DISPLAY INVISIBLE (-5705 3445);
FORCEPROP 1 LAST BODY_TYPE PLUMBING
J 0
(-5975 3525);
DISPLAY 2.276596 (-5975 3525);
PAINT GREEN (-5975 3525);
DISPLAY INVISIBLE (-5975 3525);
FORCEPROP 2 LAST CDS_LIB mstr_standard
J 0
(-6025 3575);
PAINT MONO (-6025 3575);
DISPLAY INVISIBLE (-6025 3575);
FORCEPROP 1 LAST PATH I25
J 0
(-6027 3575);
DISPLAY 0.872340 (-6027 3575);
PAINT GREEN (-6027 3575);
DISPLAY INVISIBLE (-6027 3575);
FORCEADD TAP..3
(-5825 3575);
FORCEPROP 3 LASTPIN (-5825 3525) SIG_NAME P3E_CPU0_PE1_PCH_TXN<14>
J 0
(-5815 3535);
DISPLAY 0.659574 (-5815 3535);
PAINT MONO (-5815 3535);
DISPLAY INVISIBLE (-5815 3535);
FORCEPROP 1 LASTPIN (-5825 3525) BN 14
R 1
J 0
(-5832 3513);
DISPLAY 0.680851 (-5832 3513);
PAINT GREEN (-5832 3513);
FORCEPROP 1 LAST HDL_TAP TRUE
J 0
(-5505 3445);
DISPLAY 2.276596 (-5505 3445);
PAINT GREEN (-5505 3445);
DISPLAY INVISIBLE (-5505 3445);
FORCEPROP 1 LAST BODY_TYPE PLUMBING
J 0
(-5775 3525);
DISPLAY 2.276596 (-5775 3525);
PAINT GREEN (-5775 3525);
DISPLAY INVISIBLE (-5775 3525);
FORCEPROP 2 LAST CDS_LIB mstr_standard
J 0
(-5825 3575);
PAINT MONO (-5825 3575);
DISPLAY INVISIBLE (-5825 3575);
FORCEPROP 1 LAST PATH I26
J 0
(-5827 3575);
DISPLAY 0.872340 (-5827 3575);
PAINT GREEN (-5827 3575);
DISPLAY INVISIBLE (-5827 3575);
FORCEADD TAP..3
(-5625 3575);
FORCEPROP 3 LASTPIN (-5625 3525) SIG_NAME P3E_CPU0_PE1_PCH_TXN<13>
J 0
(-5615 3535);
DISPLAY 0.659574 (-5615 3535);
PAINT MONO (-5615 3535);
DISPLAY INVISIBLE (-5615 3535);
FORCEPROP 1 LASTPIN (-5625 3525) BN 13
R 1
J 0
(-5632 3513);
DISPLAY 0.680851 (-5632 3513);
PAINT GREEN (-5632 3513);
FORCEPROP 1 LAST HDL_TAP TRUE
J 0
(-5305 3445);
DISPLAY 2.276596 (-5305 3445);
PAINT GREEN (-5305 3445);
DISPLAY INVISIBLE (-5305 3445);
FORCEPROP 1 LAST BODY_TYPE PLUMBING
J 0
(-5575 3525);
DISPLAY 2.276596 (-5575 3525);
PAINT GREEN (-5575 3525);
DISPLAY INVISIBLE (-5575 3525);
FORCEPROP 2 LAST CDS_LIB mstr_standard
J 0
(-5625 3575);
PAINT MONO (-5625 3575);
DISPLAY INVISIBLE (-5625 3575);
FORCEPROP 1 LAST PATH I27
J 0
(-5627 3575);
DISPLAY 0.872340 (-5627 3575);
PAINT GREEN (-5627 3575);
DISPLAY INVISIBLE (-5627 3575);
FORCEADD CAP..1
R 2
(-5625 3025);
FORCEPROP 1 LAST VOLTAGE 16V
J 2
(-5675 3025);
DISPLAY 0.617021 (-5675 3025);
PAINT SKYBLUE (-5675 3025);
FORCEPROP 1 LAST $LOCATION C828
J 2
(-5675 3125);
DISPLAY 0.617021 (-5675 3125);
PAINT AQUA (-5675 3125);
FORCEPROP 1 LAST VALUE 0.22UF
J 2
(-5675 3075);
DISPLAY 0.617021 (-5675 3075);
PAINT SKYBLUE (-5675 3075);
FORCEPROP 1 LAST PART_NUMBER A36096-155
J 2
(-5675 2875);
DISPLAY 0.617021 (-5675 2875);
PAINT BLUE (-5675 2875);
FORCEPROP 1 LAST PACK_TYPE 0402
J 2
(-5675 2825);
DISPLAY 0.617021 (-5675 2825);
PAINT SKYBLUE (-5675 2825);
FORCEPROP 1 LAST MATERIAL X7R
J 2
(-5675 2925);
DISPLAY 0.617021 (-5675 2925);
PAINT SKYBLUE (-5675 2925);
FORCEPROP 1 LAST TOLERANCE 10%
J 2
(-5675 2975);
DISPLAY 0.617021 (-5675 2975);
PAINT SKYBLUE (-5675 2975);
FORCEPROP 2 LAST ROOM OCP_STEERING
J 2
(-5625 3025);
PAINT MONO (-5625 3025);
DISPLAY INVISIBLE (-5625 3025);
FORCEPROP 2 LAST CDS_LIB mstr_discrete
J 0
(-5625 3025);
PAINT MONO (-5625 3025);
DISPLAY INVISIBLE (-5625 3025);
FORCEPROP 1 LASTPIN (-5625 2925) $PN 2
J 2
(-5635 2905);
DISPLAY 0.787234 (-5635 2905);
PAINT ORANGE (-5635 2905);
DISPLAY INVISIBLE (-5635 2905);
FORCEPROP 1 LASTPIN (-5625 3125) $PN 1
J 2
(-5635 3105);
DISPLAY 0.787234 (-5635 3105);
PAINT ORANGE (-5635 3105);
DISPLAY INVISIBLE (-5635 3105);
FORCEPROP 2 LAST CDS_LOCATION C828
J 2
(-5675 3125);
DISPLAY 0.617021 (-5675 3125);
PAINT AQUA (-5675 3125);
DISPLAY INVISIBLE (-5675 3125);
FORCEPROP 0 LAST $SEC 1
J 0
(-5675 3175);
PAINT MONO (-5675 3175);
DISPLAY INVISIBLE (-5675 3175);
FORCEPROP 0 LAST CDS_SEC 1
J 0
(-5675 3175);
PAINT MONO (-5675 3175);
DISPLAY INVISIBLE (-5675 3175);
FORCEPROP 1 LAST PATH I28
J 2
(-5675 3175);
DISPLAY 0.978723 (-5675 3175);
PAINT WHITE (-5675 3175);
DISPLAY INVISIBLE (-5675 3175);
FORCEADD CAP..1
R 2
(-5425 3325);
FORCEPROP 1 LAST VALUE 0.22UF
J 2
(-5475 3375);
DISPLAY 0.617021 (-5475 3375);
PAINT SKYBLUE (-5475 3375);
FORCEPROP 1 LAST PART_NUMBER A36096-155
J 2
(-5475 3175);
DISPLAY 0.617021 (-5475 3175);
PAINT BLUE (-5475 3175);
FORCEPROP 1 LAST PACK_TYPE 0402
J 2
(-5475 3125);
DISPLAY 0.617021 (-5475 3125);
PAINT SKYBLUE (-5475 3125);
FORCEPROP 1 LAST MATERIAL X7R
J 2
(-5475 3225);
DISPLAY 0.617021 (-5475 3225);
PAINT SKYBLUE (-5475 3225);
FORCEPROP 1 LAST TOLERANCE 10%
J 2
(-5475 3275);
DISPLAY 0.617021 (-5475 3275);
PAINT SKYBLUE (-5475 3275);
FORCEPROP 1 LAST VOLTAGE 16V
J 2
(-5475 3325);
DISPLAY 0.617021 (-5475 3325);
PAINT SKYBLUE (-5475 3325);
FORCEPROP 1 LAST $LOCATION C840
J 2
(-5475 3425);
DISPLAY 0.617021 (-5475 3425);
PAINT AQUA (-5475 3425);
FORCEPROP 2 LAST ROOM OCP_STEERING
J 2
(-5425 3325);
PAINT MONO (-5425 3325);
DISPLAY INVISIBLE (-5425 3325);
FORCEPROP 2 LAST CDS_LIB mstr_discrete
J 0
(-5425 3325);
PAINT MONO (-5425 3325);
DISPLAY INVISIBLE (-5425 3325);
FORCEPROP 1 LASTPIN (-5425 3225) $PN 2
J 2
(-5435 3205);
DISPLAY 0.787234 (-5435 3205);
PAINT ORANGE (-5435 3205);
DISPLAY INVISIBLE (-5435 3205);
FORCEPROP 1 LASTPIN (-5425 3425) $PN 1
J 2
(-5435 3405);
DISPLAY 0.787234 (-5435 3405);
PAINT ORANGE (-5435 3405);
DISPLAY INVISIBLE (-5435 3405);
FORCEPROP 2 LAST CDS_LOCATION C840
J 2
(-5475 3425);
DISPLAY 0.617021 (-5475 3425);
PAINT AQUA (-5475 3425);
DISPLAY INVISIBLE (-5475 3425);
FORCEPROP 0 LAST $SEC 1
J 0
(-5475 3475);
PAINT MONO (-5475 3475);
DISPLAY INVISIBLE (-5475 3475);
FORCEPROP 0 LAST CDS_SEC 1
J 0
(-5475 3475);
PAINT MONO (-5475 3475);
DISPLAY INVISIBLE (-5475 3475);
FORCEPROP 1 LAST PATH I29
J 2
(-5475 3475);
DISPLAY 0.978723 (-5475 3475);
PAINT WHITE (-5475 3475);
DISPLAY INVISIBLE (-5475 3475);
FORCEADD TAP..7
(-5725 1475);
FORCEPROP 3 LASTPIN (-5725 1525) SIG_NAME P3E_CPU0_PE1_PCH_CON_TXP<14>
J 0
(-5715 1535);
DISPLAY 0.659574 (-5715 1535);
PAINT MONO (-5715 1535);
DISPLAY INVISIBLE (-5715 1535);
FORCEPROP 1 LASTPIN (-5725 1525) BN 14
R 1
J 0
(-5732 1473);
DISPLAY 0.680851 (-5732 1473);
PAINT GREEN (-5732 1473);
FORCEPROP 1 LAST HDL_TAP TRUE
J 0
(-5405 1345);
DISPLAY 2.276596 (-5405 1345);
PAINT GREEN (-5405 1345);
DISPLAY INVISIBLE (-5405 1345);
FORCEPROP 1 LAST BODY_TYPE PLUMBING
J 0
(-5675 1475);
DISPLAY 2.276596 (-5675 1475);
PAINT GREEN (-5675 1475);
DISPLAY INVISIBLE (-5675 1475);
FORCEPROP 2 LAST CDS_LIB mstr_standard
J 0
(-5725 1475);
PAINT MONO (-5725 1475);
DISPLAY INVISIBLE (-5725 1475);
FORCEPROP 1 LAST PATH I3
J 0
(-5727 1475);
DISPLAY 0.872340 (-5727 1475);
PAINT GREEN (-5727 1475);
DISPLAY INVISIBLE (-5727 1475);
FORCEADD CAP..1
R 2
(-5225 3025);
FORCEPROP 1 LAST PART_NUMBER A36096-155
J 2
(-5275 2875);
DISPLAY 0.617021 (-5275 2875);
PAINT BLUE (-5275 2875);
FORCEPROP 1 LAST VALUE 0.22UF
J 2
(-5275 3075);
DISPLAY 0.617021 (-5275 3075);
PAINT SKYBLUE (-5275 3075);
FORCEPROP 1 LAST PACK_TYPE 0402
J 2
(-5275 2825);
DISPLAY 0.617021 (-5275 2825);
PAINT SKYBLUE (-5275 2825);
FORCEPROP 1 LAST VOLTAGE 16V
J 2
(-5275 3025);
DISPLAY 0.617021 (-5275 3025);
PAINT SKYBLUE (-5275 3025);
FORCEPROP 1 LAST TOLERANCE 10%
J 2
(-5275 2975);
DISPLAY 0.617021 (-5275 2975);
PAINT SKYBLUE (-5275 2975);
FORCEPROP 1 LAST $LOCATION C832
J 2
(-5275 3125);
DISPLAY 0.617021 (-5275 3125);
PAINT AQUA (-5275 3125);
FORCEPROP 1 LAST MATERIAL X7R
J 2
(-5275 2925);
DISPLAY 0.617021 (-5275 2925);
PAINT SKYBLUE (-5275 2925);
FORCEPROP 2 LAST ROOM OCP_STEERING
J 2
(-5225 3025);
PAINT MONO (-5225 3025);
DISPLAY INVISIBLE (-5225 3025);
FORCEPROP 2 LAST CDS_LIB mstr_discrete
J 0
(-5225 3025);
PAINT MONO (-5225 3025);
DISPLAY INVISIBLE (-5225 3025);
FORCEPROP 1 LASTPIN (-5225 2925) $PN 2
J 2
(-5235 2905);
DISPLAY 0.787234 (-5235 2905);
PAINT ORANGE (-5235 2905);
DISPLAY INVISIBLE (-5235 2905);
FORCEPROP 1 LASTPIN (-5225 3125) $PN 1
J 2
(-5235 3105);
DISPLAY 0.787234 (-5235 3105);
PAINT ORANGE (-5235 3105);
DISPLAY INVISIBLE (-5235 3105);
FORCEPROP 2 LAST CDS_LOCATION C832
J 2
(-5275 3125);
DISPLAY 0.617021 (-5275 3125);
PAINT AQUA (-5275 3125);
DISPLAY INVISIBLE (-5275 3125);
FORCEPROP 0 LAST $SEC 1
J 0
(-5275 3175);
PAINT MONO (-5275 3175);
DISPLAY INVISIBLE (-5275 3175);
FORCEPROP 0 LAST CDS_SEC 1
J 0
(-5275 3175);
PAINT MONO (-5275 3175);
DISPLAY INVISIBLE (-5275 3175);
FORCEPROP 1 LAST PATH I30
J 2
(-5275 3175);
DISPLAY 0.978723 (-5275 3175);
PAINT WHITE (-5275 3175);
DISPLAY INVISIBLE (-5275 3175);
FORCEADD TAP..3
(-5425 3575);
FORCEPROP 3 LASTPIN (-5425 3525) SIG_NAME P3E_CPU0_PE1_PCH_TXN<12>
J 0
(-5415 3535);
DISPLAY 0.659574 (-5415 3535);
PAINT MONO (-5415 3535);
DISPLAY INVISIBLE (-5415 3535);
FORCEPROP 1 LASTPIN (-5425 3525) BN 12
R 1
J 0
(-5432 3513);
DISPLAY 0.680851 (-5432 3513);
PAINT GREEN (-5432 3513);
FORCEPROP 1 LAST HDL_TAP TRUE
J 0
(-5105 3445);
DISPLAY 2.276596 (-5105 3445);
PAINT GREEN (-5105 3445);
DISPLAY INVISIBLE (-5105 3445);
FORCEPROP 1 LAST BODY_TYPE PLUMBING
J 0
(-5375 3525);
DISPLAY 2.276596 (-5375 3525);
PAINT GREEN (-5375 3525);
DISPLAY INVISIBLE (-5375 3525);
FORCEPROP 2 LAST CDS_LIB mstr_standard
J 0
(-5425 3575);
PAINT MONO (-5425 3575);
DISPLAY INVISIBLE (-5425 3575);
FORCEPROP 1 LAST PATH I31
J 0
(-5427 3575);
DISPLAY 0.872340 (-5427 3575);
PAINT GREEN (-5427 3575);
DISPLAY INVISIBLE (-5427 3575);
FORCEADD TAP..3
(-5225 3575);
FORCEPROP 3 LASTPIN (-5225 3525) SIG_NAME P3E_CPU0_PE1_PCH_TXN<11>
J 0
(-5215 3535);
DISPLAY 0.659574 (-5215 3535);
PAINT MONO (-5215 3535);
DISPLAY INVISIBLE (-5215 3535);
FORCEPROP 1 LASTPIN (-5225 3525) BN 11
R 1
J 0
(-5232 3513);
DISPLAY 0.680851 (-5232 3513);
PAINT GREEN (-5232 3513);
FORCEPROP 1 LAST HDL_TAP TRUE
J 0
(-4905 3445);
DISPLAY 2.276596 (-4905 3445);
PAINT GREEN (-4905 3445);
DISPLAY INVISIBLE (-4905 3445);
FORCEPROP 1 LAST BODY_TYPE PLUMBING
J 0
(-5175 3525);
DISPLAY 2.276596 (-5175 3525);
PAINT GREEN (-5175 3525);
DISPLAY INVISIBLE (-5175 3525);
FORCEPROP 2 LAST CDS_LIB mstr_standard
J 0
(-5225 3575);
PAINT MONO (-5225 3575);
DISPLAY INVISIBLE (-5225 3575);
FORCEPROP 1 LAST PATH I32
J 0
(-5227 3575);
DISPLAY 0.872340 (-5227 3575);
PAINT GREEN (-5227 3575);
DISPLAY INVISIBLE (-5227 3575);
FORCEADD TAP..7
(-4925 1475);
FORCEPROP 3 LASTPIN (-4925 1525) SIG_NAME P3E_CPU0_PE1_PCH_CON_TXP<10>
J 0
(-4915 1535);
DISPLAY 0.659574 (-4915 1535);
PAINT MONO (-4915 1535);
DISPLAY INVISIBLE (-4915 1535);
FORCEPROP 1 LASTPIN (-4925 1525) BN 10
R 1
J 0
(-4932 1473);
DISPLAY 0.680851 (-4932 1473);
PAINT GREEN (-4932 1473);
FORCEPROP 1 LAST HDL_TAP TRUE
J 0
(-4605 1345);
DISPLAY 2.276596 (-4605 1345);
PAINT GREEN (-4605 1345);
DISPLAY INVISIBLE (-4605 1345);
FORCEPROP 1 LAST BODY_TYPE PLUMBING
J 0
(-4875 1475);
DISPLAY 2.276596 (-4875 1475);
PAINT GREEN (-4875 1475);
DISPLAY INVISIBLE (-4875 1475);
FORCEPROP 2 LAST CDS_LIB mstr_standard
J 0
(-4925 1475);
PAINT MONO (-4925 1475);
DISPLAY INVISIBLE (-4925 1475);
FORCEPROP 1 LAST PATH I33
J 0
(-4927 1475);
DISPLAY 0.872340 (-4927 1475);
PAINT GREEN (-4927 1475);
DISPLAY INVISIBLE (-4927 1475);
FORCEADD TAP..7
(-4725 1475);
FORCEPROP 3 LASTPIN (-4725 1525) SIG_NAME P3E_CPU0_PE1_PCH_CON_TXP<9>
J 0
(-4715 1535);
DISPLAY 0.659574 (-4715 1535);
PAINT MONO (-4715 1535);
DISPLAY INVISIBLE (-4715 1535);
FORCEPROP 1 LASTPIN (-4725 1525) BN 9
R 1
J 0
(-4732 1473);
DISPLAY 0.680851 (-4732 1473);
PAINT GREEN (-4732 1473);
FORCEPROP 1 LAST HDL_TAP TRUE
J 0
(-4405 1345);
DISPLAY 2.276596 (-4405 1345);
PAINT GREEN (-4405 1345);
DISPLAY INVISIBLE (-4405 1345);
FORCEPROP 1 LAST BODY_TYPE PLUMBING
J 0
(-4675 1475);
DISPLAY 2.276596 (-4675 1475);
PAINT GREEN (-4675 1475);
DISPLAY INVISIBLE (-4675 1475);
FORCEPROP 2 LAST CDS_LIB mstr_standard
J 0
(-4725 1475);
PAINT MONO (-4725 1475);
DISPLAY INVISIBLE (-4725 1475);
FORCEPROP 1 LAST PATH I34
J 0
(-4727 1475);
DISPLAY 0.872340 (-4727 1475);
PAINT GREEN (-4727 1475);
DISPLAY INVISIBLE (-4727 1475);
FORCEADD CAP..1
R 2
(-4725 1725);
FORCEPROP 1 LAST TOLERANCE 10%
J 2
(-4775 1675);
DISPLAY 0.617021 (-4775 1675);
PAINT SKYBLUE (-4775 1675);
FORCEPROP 1 LAST VOLTAGE 16V
J 2
(-4775 1725);
DISPLAY 0.617021 (-4775 1725);
PAINT SKYBLUE (-4775 1725);
FORCEPROP 1 LAST $LOCATION C845
J 2
(-4775 1825);
DISPLAY 0.617021 (-4775 1825);
PAINT AQUA (-4775 1825);
FORCEPROP 1 LAST VALUE 0.22UF
J 2
(-4775 1775);
DISPLAY 0.617021 (-4775 1775);
PAINT SKYBLUE (-4775 1775);
FORCEPROP 1 LAST MATERIAL X7R
J 2
(-4775 1625);
DISPLAY 0.617021 (-4775 1625);
PAINT SKYBLUE (-4775 1625);
FORCEPROP 1 LAST PART_NUMBER A36096-155
J 2
(-4775 1575);
DISPLAY 0.617021 (-4775 1575);
PAINT BLUE (-4775 1575);
FORCEPROP 1 LAST PACK_TYPE 0402
J 2
(-4775 1525);
DISPLAY 0.617021 (-4775 1525);
PAINT SKYBLUE (-4775 1525);
FORCEPROP 2 LAST ROOM OCP_STEERING
J 2
(-4725 1725);
PAINT MONO (-4725 1725);
DISPLAY INVISIBLE (-4725 1725);
FORCEPROP 2 LAST CDS_LIB mstr_discrete
J 0
(-4725 1725);
PAINT MONO (-4725 1725);
DISPLAY INVISIBLE (-4725 1725);
FORCEPROP 1 LASTPIN (-4725 1625) $PN 2
J 2
(-4735 1605);
DISPLAY 0.787234 (-4735 1605);
PAINT ORANGE (-4735 1605);
DISPLAY INVISIBLE (-4735 1605);
FORCEPROP 1 LASTPIN (-4725 1825) $PN 1
J 2
(-4735 1805);
DISPLAY 0.787234 (-4735 1805);
PAINT ORANGE (-4735 1805);
DISPLAY INVISIBLE (-4735 1805);
FORCEPROP 2 LAST CDS_LOCATION C845
J 2
(-4775 1825);
DISPLAY 0.617021 (-4775 1825);
PAINT AQUA (-4775 1825);
DISPLAY INVISIBLE (-4775 1825);
FORCEPROP 0 LAST $SEC 1
J 0
(-4775 1875);
PAINT MONO (-4775 1875);
DISPLAY INVISIBLE (-4775 1875);
FORCEPROP 0 LAST CDS_SEC 1
J 0
(-4775 1875);
PAINT MONO (-4775 1875);
DISPLAY INVISIBLE (-4775 1875);
FORCEPROP 1 LAST PATH I35
J 2
(-4775 1875);
DISPLAY 0.978723 (-4775 1875);
PAINT WHITE (-4775 1875);
DISPLAY INVISIBLE (-4775 1875);
FORCEADD TAP..7
(-4525 1475);
FORCEPROP 3 LASTPIN (-4525 1525) SIG_NAME P3E_CPU0_PE1_PCH_CON_TXP<8>
J 0
(-4515 1535);
DISPLAY 0.659574 (-4515 1535);
PAINT MONO (-4515 1535);
DISPLAY INVISIBLE (-4515 1535);
FORCEPROP 1 LASTPIN (-4525 1525) BN 8
R 1
J 0
(-4532 1473);
DISPLAY 0.680851 (-4532 1473);
PAINT GREEN (-4532 1473);
FORCEPROP 1 LAST HDL_TAP TRUE
J 0
(-4205 1345);
DISPLAY 2.276596 (-4205 1345);
PAINT GREEN (-4205 1345);
DISPLAY INVISIBLE (-4205 1345);
FORCEPROP 1 LAST BODY_TYPE PLUMBING
J 0
(-4475 1475);
DISPLAY 2.276596 (-4475 1475);
PAINT GREEN (-4475 1475);
DISPLAY INVISIBLE (-4475 1475);
FORCEPROP 2 LAST CDS_LIB mstr_standard
J 0
(-4525 1475);
PAINT MONO (-4525 1475);
DISPLAY INVISIBLE (-4525 1475);
FORCEPROP 1 LAST PATH I36
J 0
(-4527 1475);
DISPLAY 0.872340 (-4527 1475);
PAINT GREEN (-4527 1475);
DISPLAY INVISIBLE (-4527 1475);
FORCEADD OFFPAGE..2
(-4225 1425);
FORCEPROP 2 LAST $XR0 108 
J 0
(-4036 1425);
DISPLAY 0.638298 (-4036 1425);
PAINT MONO (-4036 1425);
FORCEPROP 1 LAST COMMENT_BODY TRUE
J 0
(-4270 1330);
DISPLAY 0.872340 (-4270 1330);
PAINT GREEN (-4270 1330);
DISPLAY INVISIBLE (-4270 1330);
FORCEPROP 1 LAST OFFPAGE TRUE
J 0
(-3900 1300);
DISPLAY 0.872340 (-3900 1300);
PAINT GREEN (-3900 1300);
DISPLAY INVISIBLE (-3900 1300);
FORCEPROP 2 LAST CDS_LIB mstr_standard
J 0
(-4225 1425);
PAINT MONO (-4225 1425);
DISPLAY INVISIBLE (-4225 1425);
FORCEPROP 2 LAST PATH I37
J 0
(-4025 1475);
DISPLAY 1.021277 (-4025 1475);
PAINT ORANGE (-4025 1475);
DISPLAY INVISIBLE (-4025 1475);
FORCEADD TAP..7
(-3425 1475);
FORCEPROP 3 LASTPIN (-3425 1525) SIG_NAME P3E_CPU0_PE1_PCH_CON_RXP<15>
J 0
(-3415 1535);
DISPLAY 0.659574 (-3415 1535);
PAINT MONO (-3415 1535);
DISPLAY INVISIBLE (-3415 1535);
FORCEPROP 1 LASTPIN (-3425 1525) BN 15
R 1
J 0
(-3432 1473);
DISPLAY 0.680851 (-3432 1473);
PAINT GREEN (-3432 1473);
FORCEPROP 1 LAST HDL_TAP TRUE
J 0
(-3105 1345);
DISPLAY 2.276596 (-3105 1345);
PAINT GREEN (-3105 1345);
DISPLAY INVISIBLE (-3105 1345);
FORCEPROP 1 LAST BODY_TYPE PLUMBING
J 0
(-3375 1475);
DISPLAY 2.276596 (-3375 1475);
PAINT GREEN (-3375 1475);
DISPLAY INVISIBLE (-3375 1475);
FORCEPROP 2 LAST CDS_LIB mstr_standard
J 0
(-3425 1475);
PAINT MONO (-3425 1475);
DISPLAY INVISIBLE (-3425 1475);
FORCEPROP 1 LAST PATH I38
J 0
(-3427 1475);
DISPLAY 0.872340 (-3427 1475);
PAINT GREEN (-3427 1475);
DISPLAY INVISIBLE (-3427 1475);
FORCEADD RES..2
(-3425 1725);
FORCEPROP 1 LAST $LOCATION R767
J 0
(-3380 1850);
DISPLAY 0.617021 (-3380 1850);
PAINT AQUA (-3380 1850);
FORCEPROP 1 LAST WATTAGE 1/16W
J 0
(-3385 1700);
DISPLAY 0.617021 (-3385 1700);
PAINT SKYBLUE (-3385 1700);
FORCEPROP 1 LAST PACK_TYPE 0402
J 0
(-3385 1550);
DISPLAY 0.617021 (-3385 1550);
PAINT SKYBLUE (-3385 1550);
FORCEPROP 1 LAST PART_NUMBER G21497-005
J 0
(-3385 1600);
DISPLAY 0.617021 (-3385 1600);
PAINT BLUE (-3385 1600);
FORCEPROP 1 LAST TOLERANCE 5%
J 0
(-3380 1750);
DISPLAY 0.617021 (-3380 1750);
PAINT SKYBLUE (-3380 1750);
FORCEPROP 1 LAST MATERIAL CHIP
J 0
(-3385 1650);
DISPLAY 0.617021 (-3385 1650);
PAINT SKYBLUE (-3385 1650);
FORCEPROP 1 LAST VALUE 0.0
J 0
(-3380 1800);
DISPLAY 0.617021 (-3380 1800);
PAINT SKYBLUE (-3380 1800);
FORCEPROP 2 LAST ROOM PCIE_STEERING
J 0
(-3375 1900);
PAINT MONO (-3375 1900);
DISPLAY INVISIBLE (-3375 1900);
FORCEPROP 2 LAST CDS_LIB mstr_discrete
J 0
(-3425 1725);
PAINT MONO (-3425 1725);
DISPLAY INVISIBLE (-3425 1725);
FORCEPROP 1 LASTPIN (-3425 1625) $PN 2
J 0
(-3420 1635);
DISPLAY 0.787234 (-3420 1635);
PAINT ORANGE (-3420 1635);
DISPLAY INVISIBLE (-3420 1635);
FORCEPROP 1 LASTPIN (-3425 1825) $PN 1
J 0
(-3420 1787);
DISPLAY 0.787234 (-3420 1787);
PAINT ORANGE (-3420 1787);
DISPLAY INVISIBLE (-3420 1787);
FORCEPROP 0 LAST CDS_LOCATION R767
J 0
(-3375 1900);
PAINT MONO (-3375 1900);
DISPLAY INVISIBLE (-3375 1900);
FORCEPROP 0 LAST $SEC 1
J 0
(-3375 1900);
PAINT MONO (-3375 1900);
DISPLAY INVISIBLE (-3375 1900);
FORCEPROP 0 LAST CDS_SEC 1
J 0
(-3375 1900);
PAINT MONO (-3375 1900);
DISPLAY INVISIBLE (-3375 1900);
FORCEPROP 1 LAST PATH I39
J 0
(-3375 1900);
DISPLAY 0.978723 (-3375 1900);
PAINT WHITE (-3375 1900);
DISPLAY INVISIBLE (-3375 1900);
FORCEADD TAP..7
(-5525 1475);
FORCEPROP 3 LASTPIN (-5525 1525) SIG_NAME P3E_CPU0_PE1_PCH_CON_TXP<13>
J 0
(-5515 1535);
DISPLAY 0.659574 (-5515 1535);
PAINT MONO (-5515 1535);
DISPLAY INVISIBLE (-5515 1535);
FORCEPROP 1 LASTPIN (-5525 1525) BN 13
R 1
J 0
(-5532 1473);
DISPLAY 0.680851 (-5532 1473);
PAINT GREEN (-5532 1473);
FORCEPROP 1 LAST HDL_TAP TRUE
J 0
(-5205 1345);
DISPLAY 2.276596 (-5205 1345);
PAINT GREEN (-5205 1345);
DISPLAY INVISIBLE (-5205 1345);
FORCEPROP 1 LAST BODY_TYPE PLUMBING
J 0
(-5475 1475);
DISPLAY 2.276596 (-5475 1475);
PAINT GREEN (-5475 1475);
DISPLAY INVISIBLE (-5475 1475);
FORCEPROP 2 LAST CDS_LIB mstr_standard
J 0
(-5525 1475);
PAINT MONO (-5525 1475);
DISPLAY INVISIBLE (-5525 1475);
FORCEPROP 1 LAST PATH I4
J 0
(-5527 1475);
DISPLAY 0.872340 (-5527 1475);
PAINT GREEN (-5527 1475);
DISPLAY INVISIBLE (-5527 1475);
FORCEADD TAP..7
(-3225 1475);
FORCEPROP 3 LASTPIN (-3225 1525) SIG_NAME P3E_CPU0_PE1_PCH_CON_RXP<14>
J 0
(-3215 1535);
DISPLAY 0.659574 (-3215 1535);
PAINT MONO (-3215 1535);
DISPLAY INVISIBLE (-3215 1535);
FORCEPROP 1 LASTPIN (-3225 1525) BN 14
R 1
J 0
(-3232 1473);
DISPLAY 0.680851 (-3232 1473);
PAINT GREEN (-3232 1473);
FORCEPROP 1 LAST HDL_TAP TRUE
J 0
(-2905 1345);
DISPLAY 2.276596 (-2905 1345);
PAINT GREEN (-2905 1345);
DISPLAY INVISIBLE (-2905 1345);
FORCEPROP 1 LAST BODY_TYPE PLUMBING
J 0
(-3175 1475);
DISPLAY 2.276596 (-3175 1475);
PAINT GREEN (-3175 1475);
DISPLAY INVISIBLE (-3175 1475);
FORCEPROP 2 LAST CDS_LIB mstr_standard
J 0
(-3225 1475);
PAINT MONO (-3225 1475);
DISPLAY INVISIBLE (-3225 1475);
FORCEPROP 1 LAST PATH I40
J 0
(-3227 1475);
DISPLAY 0.872340 (-3227 1475);
PAINT GREEN (-3227 1475);
DISPLAY INVISIBLE (-3227 1475);
FORCEADD CAP..1
R 2
(-4925 2025);
FORCEPROP 1 LAST PART_NUMBER A36096-155
J 2
(-4975 1875);
DISPLAY 0.617021 (-4975 1875);
PAINT BLUE (-4975 1875);
FORCEPROP 1 LAST MATERIAL X7R
J 2
(-4975 1925);
DISPLAY 0.617021 (-4975 1925);
PAINT SKYBLUE (-4975 1925);
FORCEPROP 1 LAST VALUE 0.22UF
J 2
(-4975 2075);
DISPLAY 0.617021 (-4975 2075);
PAINT SKYBLUE (-4975 2075);
FORCEPROP 1 LAST $LOCATION C835
J 2
(-4975 2125);
DISPLAY 0.617021 (-4975 2125);
PAINT AQUA (-4975 2125);
FORCEPROP 1 LAST TOLERANCE 10%
J 2
(-4975 1975);
DISPLAY 0.617021 (-4975 1975);
PAINT SKYBLUE (-4975 1975);
FORCEPROP 1 LAST VOLTAGE 16V
J 2
(-4975 2025);
DISPLAY 0.617021 (-4975 2025);
PAINT SKYBLUE (-4975 2025);
FORCEPROP 1 LAST PACK_TYPE 0402
J 2
(-4975 1825);
DISPLAY 0.617021 (-4975 1825);
PAINT SKYBLUE (-4975 1825);
FORCEPROP 2 LAST ROOM OCP_STEERING
J 2
(-4925 2025);
PAINT MONO (-4925 2025);
DISPLAY INVISIBLE (-4925 2025);
FORCEPROP 2 LAST CDS_LIB mstr_discrete
J 0
(-4925 2025);
PAINT MONO (-4925 2025);
DISPLAY INVISIBLE (-4925 2025);
FORCEPROP 1 LASTPIN (-4925 1925) $PN 2
J 2
(-4935 1905);
DISPLAY 0.787234 (-4935 1905);
PAINT ORANGE (-4935 1905);
DISPLAY INVISIBLE (-4935 1905);
FORCEPROP 1 LASTPIN (-4925 2125) $PN 1
J 2
(-4935 2105);
DISPLAY 0.787234 (-4935 2105);
PAINT ORANGE (-4935 2105);
DISPLAY INVISIBLE (-4935 2105);
FORCEPROP 2 LAST CDS_LOCATION C835
J 2
(-4975 2125);
DISPLAY 0.617021 (-4975 2125);
PAINT AQUA (-4975 2125);
DISPLAY INVISIBLE (-4975 2125);
FORCEPROP 0 LAST $SEC 1
J 0
(-4975 2175);
PAINT MONO (-4975 2175);
DISPLAY INVISIBLE (-4975 2175);
FORCEPROP 0 LAST CDS_SEC 1
J 0
(-4975 2175);
PAINT MONO (-4975 2175);
DISPLAY INVISIBLE (-4975 2175);
FORCEPROP 1 LAST PATH I41
J 2
(-4975 2175);
DISPLAY 0.978723 (-4975 2175);
PAINT WHITE (-4975 2175);
DISPLAY INVISIBLE (-4975 2175);
FORCEADD TAP..3
(-4925 2275);
FORCEPROP 3 LASTPIN (-4925 2225) SIG_NAME P3E_CPU0_PE1_PCH_TXP<10>
J 0
(-4915 2235);
DISPLAY 0.659574 (-4915 2235);
PAINT MONO (-4915 2235);
DISPLAY INVISIBLE (-4915 2235);
FORCEPROP 1 LASTPIN (-4925 2225) BN 10
R 1
J 0
(-4932 2213);
DISPLAY 0.680851 (-4932 2213);
PAINT GREEN (-4932 2213);
FORCEPROP 1 LAST HDL_TAP TRUE
J 0
(-4605 2145);
DISPLAY 2.276596 (-4605 2145);
PAINT GREEN (-4605 2145);
DISPLAY INVISIBLE (-4605 2145);
FORCEPROP 1 LAST BODY_TYPE PLUMBING
J 0
(-4875 2225);
DISPLAY 2.276596 (-4875 2225);
PAINT GREEN (-4875 2225);
DISPLAY INVISIBLE (-4875 2225);
FORCEPROP 2 LAST CDS_LIB mstr_standard
J 0
(-4925 2275);
PAINT MONO (-4925 2275);
DISPLAY INVISIBLE (-4925 2275);
FORCEPROP 1 LAST PATH I42
J 0
(-4927 2275);
DISPLAY 0.872340 (-4927 2275);
PAINT GREEN (-4927 2275);
DISPLAY INVISIBLE (-4927 2275);
FORCEADD TAP..3
(-4725 2275);
FORCEPROP 3 LASTPIN (-4725 2225) SIG_NAME P3E_CPU0_PE1_PCH_TXP<9>
J 0
(-4715 2235);
DISPLAY 0.659574 (-4715 2235);
PAINT MONO (-4715 2235);
DISPLAY INVISIBLE (-4715 2235);
FORCEPROP 1 LASTPIN (-4725 2225) BN 9
R 1
J 0
(-4732 2213);
DISPLAY 0.680851 (-4732 2213);
PAINT GREEN (-4732 2213);
FORCEPROP 1 LAST HDL_TAP TRUE
J 0
(-4405 2145);
DISPLAY 2.276596 (-4405 2145);
PAINT GREEN (-4405 2145);
DISPLAY INVISIBLE (-4405 2145);
FORCEPROP 1 LAST BODY_TYPE PLUMBING
J 0
(-4675 2225);
DISPLAY 2.276596 (-4675 2225);
PAINT GREEN (-4675 2225);
DISPLAY INVISIBLE (-4675 2225);
FORCEPROP 2 LAST CDS_LIB mstr_standard
J 0
(-4725 2275);
PAINT MONO (-4725 2275);
DISPLAY INVISIBLE (-4725 2275);
FORCEPROP 1 LAST PATH I43
J 0
(-4727 2275);
DISPLAY 0.872340 (-4727 2275);
PAINT GREEN (-4727 2275);
DISPLAY INVISIBLE (-4727 2275);
FORCEADD TAP..7
(-5025 2775);
FORCEPROP 3 LASTPIN (-5025 2825) SIG_NAME P3E_CPU0_PE1_PCH_CON_TXN<10>
J 0
(-5015 2835);
DISPLAY 0.659574 (-5015 2835);
PAINT MONO (-5015 2835);
DISPLAY INVISIBLE (-5015 2835);
FORCEPROP 1 LASTPIN (-5025 2825) BN 10
R 1
J 0
(-5032 2773);
DISPLAY 0.680851 (-5032 2773);
PAINT GREEN (-5032 2773);
FORCEPROP 1 LAST HDL_TAP TRUE
J 0
(-4705 2645);
DISPLAY 2.276596 (-4705 2645);
PAINT GREEN (-4705 2645);
DISPLAY INVISIBLE (-4705 2645);
FORCEPROP 1 LAST BODY_TYPE PLUMBING
J 0
(-4975 2775);
DISPLAY 2.276596 (-4975 2775);
PAINT GREEN (-4975 2775);
DISPLAY INVISIBLE (-4975 2775);
FORCEPROP 2 LAST CDS_LIB mstr_standard
J 0
(-5025 2775);
PAINT MONO (-5025 2775);
DISPLAY INVISIBLE (-5025 2775);
FORCEPROP 1 LAST PATH I44
J 0
(-5027 2775);
DISPLAY 0.872340 (-5027 2775);
PAINT GREEN (-5027 2775);
DISPLAY INVISIBLE (-5027 2775);
FORCEADD TAP..7
(-4825 2775);
FORCEPROP 3 LASTPIN (-4825 2825) SIG_NAME P3E_CPU0_PE1_PCH_CON_TXN<9>
J 0
(-4815 2835);
DISPLAY 0.659574 (-4815 2835);
PAINT MONO (-4815 2835);
DISPLAY INVISIBLE (-4815 2835);
FORCEPROP 1 LASTPIN (-4825 2825) BN 9
R 1
J 0
(-4832 2773);
DISPLAY 0.680851 (-4832 2773);
PAINT GREEN (-4832 2773);
FORCEPROP 1 LAST HDL_TAP TRUE
J 0
(-4505 2645);
DISPLAY 2.276596 (-4505 2645);
PAINT GREEN (-4505 2645);
DISPLAY INVISIBLE (-4505 2645);
FORCEPROP 1 LAST BODY_TYPE PLUMBING
J 0
(-4775 2775);
DISPLAY 2.276596 (-4775 2775);
PAINT GREEN (-4775 2775);
DISPLAY INVISIBLE (-4775 2775);
FORCEPROP 2 LAST CDS_LIB mstr_standard
J 0
(-4825 2775);
PAINT MONO (-4825 2775);
DISPLAY INVISIBLE (-4825 2775);
FORCEPROP 1 LAST PATH I45
J 0
(-4827 2775);
DISPLAY 0.872340 (-4827 2775);
PAINT GREEN (-4827 2775);
DISPLAY INVISIBLE (-4827 2775);
FORCEADD TAP..7
(-4625 2775);
FORCEPROP 3 LASTPIN (-4625 2825) SIG_NAME P3E_CPU0_PE1_PCH_CON_TXN<8>
J 0
(-4615 2835);
DISPLAY 0.659574 (-4615 2835);
PAINT MONO (-4615 2835);
DISPLAY INVISIBLE (-4615 2835);
FORCEPROP 1 LASTPIN (-4625 2825) BN 8
R 1
J 0
(-4632 2773);
DISPLAY 0.680851 (-4632 2773);
PAINT GREEN (-4632 2773);
FORCEPROP 1 LAST HDL_TAP TRUE
J 0
(-4305 2645);
DISPLAY 2.276596 (-4305 2645);
PAINT GREEN (-4305 2645);
DISPLAY INVISIBLE (-4305 2645);
FORCEPROP 1 LAST BODY_TYPE PLUMBING
J 0
(-4575 2775);
DISPLAY 2.276596 (-4575 2775);
PAINT GREEN (-4575 2775);
DISPLAY INVISIBLE (-4575 2775);
FORCEPROP 2 LAST CDS_LIB mstr_standard
J 0
(-4625 2775);
PAINT MONO (-4625 2775);
DISPLAY INVISIBLE (-4625 2775);
FORCEPROP 1 LAST PATH I46
J 0
(-4627 2775);
DISPLAY 0.872340 (-4627 2775);
PAINT GREEN (-4627 2775);
DISPLAY INVISIBLE (-4627 2775);
FORCEADD CAP..1
R 2
(-4525 2025);
FORCEPROP 1 LAST PART_NUMBER A36096-155
J 2
(-4575 1875);
DISPLAY 0.617021 (-4575 1875);
PAINT BLUE (-4575 1875);
FORCEPROP 1 LAST TOLERANCE 10%
J 2
(-4575 1975);
DISPLAY 0.617021 (-4575 1975);
PAINT SKYBLUE (-4575 1975);
FORCEPROP 1 LAST MATERIAL X7R
J 2
(-4575 1925);
DISPLAY 0.617021 (-4575 1925);
PAINT SKYBLUE (-4575 1925);
FORCEPROP 1 LAST PACK_TYPE 0402
J 2
(-4575 1825);
DISPLAY 0.617021 (-4575 1825);
PAINT SKYBLUE (-4575 1825);
FORCEPROP 1 LAST VOLTAGE 16V
J 2
(-4575 2025);
DISPLAY 0.617021 (-4575 2025);
PAINT SKYBLUE (-4575 2025);
FORCEPROP 1 LAST VALUE 0.22UF
J 2
(-4575 2075);
DISPLAY 0.617021 (-4575 2075);
PAINT SKYBLUE (-4575 2075);
FORCEPROP 1 LAST $LOCATION C843
J 2
(-4575 2125);
DISPLAY 0.617021 (-4575 2125);
PAINT AQUA (-4575 2125);
FORCEPROP 2 LAST ROOM OCP_STEERING
J 2
(-4525 2025);
PAINT MONO (-4525 2025);
DISPLAY INVISIBLE (-4525 2025);
FORCEPROP 2 LAST CDS_LIB mstr_discrete
J 0
(-4525 2025);
PAINT MONO (-4525 2025);
DISPLAY INVISIBLE (-4525 2025);
FORCEPROP 1 LASTPIN (-4525 1925) $PN 2
J 2
(-4535 1905);
DISPLAY 0.787234 (-4535 1905);
PAINT ORANGE (-4535 1905);
DISPLAY INVISIBLE (-4535 1905);
FORCEPROP 1 LASTPIN (-4525 2125) $PN 1
J 2
(-4535 2105);
DISPLAY 0.787234 (-4535 2105);
PAINT ORANGE (-4535 2105);
DISPLAY INVISIBLE (-4535 2105);
FORCEPROP 2 LAST CDS_LOCATION C843
J 2
(-4575 2125);
DISPLAY 0.617021 (-4575 2125);
PAINT AQUA (-4575 2125);
DISPLAY INVISIBLE (-4575 2125);
FORCEPROP 0 LAST $SEC 1
J 0
(-4575 2175);
PAINT MONO (-4575 2175);
DISPLAY INVISIBLE (-4575 2175);
FORCEPROP 0 LAST CDS_SEC 1
J 0
(-4575 2175);
PAINT MONO (-4575 2175);
DISPLAY INVISIBLE (-4575 2175);
FORCEPROP 1 LAST PATH I47
J 2
(-4575 2175);
DISPLAY 0.978723 (-4575 2175);
PAINT WHITE (-4575 2175);
DISPLAY INVISIBLE (-4575 2175);
FORCEADD TAP..3
(-4525 2275);
FORCEPROP 3 LASTPIN (-4525 2225) SIG_NAME P3E_CPU0_PE1_PCH_TXP<8>
J 0
(-4515 2235);
DISPLAY 0.659574 (-4515 2235);
PAINT MONO (-4515 2235);
DISPLAY INVISIBLE (-4515 2235);
FORCEPROP 1 LASTPIN (-4525 2225) BN 8
R 1
J 0
(-4532 2213);
DISPLAY 0.680851 (-4532 2213);
PAINT GREEN (-4532 2213);
FORCEPROP 1 LAST HDL_TAP TRUE
J 0
(-4205 2145);
DISPLAY 2.276596 (-4205 2145);
PAINT GREEN (-4205 2145);
DISPLAY INVISIBLE (-4205 2145);
FORCEPROP 1 LAST BODY_TYPE PLUMBING
J 0
(-4475 2225);
DISPLAY 2.276596 (-4475 2225);
PAINT GREEN (-4475 2225);
DISPLAY INVISIBLE (-4475 2225);
FORCEPROP 2 LAST CDS_LIB mstr_standard
J 0
(-4525 2275);
PAINT MONO (-4525 2275);
DISPLAY INVISIBLE (-4525 2275);
FORCEPROP 1 LAST PATH I48
J 0
(-4527 2275);
DISPLAY 0.872340 (-4527 2275);
PAINT GREEN (-4527 2275);
DISPLAY INVISIBLE (-4527 2275);
FORCEADD OFFPAGE..2
(-4325 2725);
FORCEPROP 2 LAST $XR0 108 
J 0
(-4136 2725);
DISPLAY 0.638298 (-4136 2725);
PAINT MONO (-4136 2725);
FORCEPROP 1 LAST COMMENT_BODY TRUE
J 0
(-4370 2630);
DISPLAY 0.872340 (-4370 2630);
PAINT GREEN (-4370 2630);
DISPLAY INVISIBLE (-4370 2630);
FORCEPROP 1 LAST OFFPAGE TRUE
J 0
(-4000 2600);
DISPLAY 0.872340 (-4000 2600);
PAINT GREEN (-4000 2600);
DISPLAY INVISIBLE (-4000 2600);
FORCEPROP 2 LAST CDS_LIB mstr_standard
J 0
(-4325 2725);
PAINT MONO (-4325 2725);
DISPLAY INVISIBLE (-4325 2725);
FORCEPROP 2 LAST PATH I49
J 0
(-4125 2775);
DISPLAY 1.021277 (-4125 2775);
PAINT ORANGE (-4125 2775);
DISPLAY INVISIBLE (-4125 2775);
FORCEADD CAP..1
R 2
(-5525 1725);
FORCEPROP 1 LAST MATERIAL X7R
J 2
(-5575 1625);
DISPLAY 0.617021 (-5575 1625);
PAINT SKYBLUE (-5575 1625);
FORCEPROP 1 LAST PART_NUMBER A36096-155
J 2
(-5575 1575);
DISPLAY 0.617021 (-5575 1575);
PAINT BLUE (-5575 1575);
FORCEPROP 1 LAST PACK_TYPE 0402
J 2
(-5575 1525);
DISPLAY 0.617021 (-5575 1525);
PAINT SKYBLUE (-5575 1525);
FORCEPROP 1 LAST VALUE 0.22UF
J 2
(-5575 1775);
DISPLAY 0.617021 (-5575 1775);
PAINT SKYBLUE (-5575 1775);
FORCEPROP 1 LAST VOLTAGE 16V
J 2
(-5575 1725);
DISPLAY 0.617021 (-5575 1725);
PAINT SKYBLUE (-5575 1725);
FORCEPROP 1 LAST TOLERANCE 10%
J 2
(-5575 1675);
DISPLAY 0.617021 (-5575 1675);
PAINT SKYBLUE (-5575 1675);
FORCEPROP 1 LAST $LOCATION C829
J 2
(-5575 1825);
DISPLAY 0.617021 (-5575 1825);
PAINT AQUA (-5575 1825);
FORCEPROP 2 LAST ROOM OCP_STEERING
J 2
(-5525 1725);
PAINT MONO (-5525 1725);
DISPLAY INVISIBLE (-5525 1725);
FORCEPROP 2 LAST CDS_LIB mstr_discrete
J 0
(-5525 1725);
PAINT MONO (-5525 1725);
DISPLAY INVISIBLE (-5525 1725);
FORCEPROP 1 LASTPIN (-5525 1625) $PN 2
J 2
(-5535 1605);
DISPLAY 0.787234 (-5535 1605);
PAINT ORANGE (-5535 1605);
DISPLAY INVISIBLE (-5535 1605);
FORCEPROP 1 LASTPIN (-5525 1825) $PN 1
J 2
(-5535 1805);
DISPLAY 0.787234 (-5535 1805);
PAINT ORANGE (-5535 1805);
DISPLAY INVISIBLE (-5535 1805);
FORCEPROP 2 LAST CDS_LOCATION C829
J 2
(-5575 1825);
DISPLAY 0.617021 (-5575 1825);
PAINT AQUA (-5575 1825);
DISPLAY INVISIBLE (-5575 1825);
FORCEPROP 0 LAST $SEC 1
J 0
(-5575 1875);
PAINT MONO (-5575 1875);
DISPLAY INVISIBLE (-5575 1875);
FORCEPROP 0 LAST CDS_SEC 1
J 0
(-5575 1875);
PAINT MONO (-5575 1875);
DISPLAY INVISIBLE (-5575 1875);
FORCEPROP 1 LAST PATH I5
J 2
(-5575 1875);
DISPLAY 0.978723 (-5575 1875);
PAINT WHITE (-5575 1875);
DISPLAY INVISIBLE (-5575 1875);
FORCEADD CAP..1
R 2
(-5025 3325);
FORCEPROP 1 LAST TOLERANCE 10%
J 2
(-5075 3275);
DISPLAY 0.617021 (-5075 3275);
PAINT SKYBLUE (-5075 3275);
FORCEPROP 1 LAST VOLTAGE 16V
J 2
(-5075 3325);
DISPLAY 0.617021 (-5075 3325);
PAINT SKYBLUE (-5075 3325);
FORCEPROP 1 LAST PACK_TYPE 0402
J 2
(-5075 3125);
DISPLAY 0.617021 (-5075 3125);
PAINT SKYBLUE (-5075 3125);
FORCEPROP 1 LAST MATERIAL X7R
J 2
(-5075 3225);
DISPLAY 0.617021 (-5075 3225);
PAINT SKYBLUE (-5075 3225);
FORCEPROP 1 LAST VALUE 0.22UF
J 2
(-5075 3375);
DISPLAY 0.617021 (-5075 3375);
PAINT SKYBLUE (-5075 3375);
FORCEPROP 1 LAST PART_NUMBER A36096-155
J 2
(-5075 3175);
DISPLAY 0.617021 (-5075 3175);
PAINT BLUE (-5075 3175);
FORCEPROP 1 LAST $LOCATION C834
J 2
(-5075 3425);
DISPLAY 0.617021 (-5075 3425);
PAINT AQUA (-5075 3425);
FORCEPROP 2 LAST CDS_LIB mstr_discrete
J 0
(-5025 3325);
PAINT MONO (-5025 3325);
DISPLAY INVISIBLE (-5025 3325);
FORCEPROP 2 LAST ROOM OCP_STEERING
J 2
(-5025 3325);
PAINT MONO (-5025 3325);
DISPLAY INVISIBLE (-5025 3325);
FORCEPROP 1 LASTPIN (-5025 3225) $PN 2
J 2
(-5035 3205);
DISPLAY 0.787234 (-5035 3205);
PAINT ORANGE (-5035 3205);
DISPLAY INVISIBLE (-5035 3205);
FORCEPROP 1 LASTPIN (-5025 3425) $PN 1
J 2
(-5035 3405);
DISPLAY 0.787234 (-5035 3405);
PAINT ORANGE (-5035 3405);
DISPLAY INVISIBLE (-5035 3405);
FORCEPROP 2 LAST CDS_LOCATION C834
J 2
(-5075 3425);
DISPLAY 0.617021 (-5075 3425);
PAINT AQUA (-5075 3425);
DISPLAY INVISIBLE (-5075 3425);
FORCEPROP 0 LAST $SEC 1
J 0
(-5075 3475);
PAINT MONO (-5075 3475);
DISPLAY INVISIBLE (-5075 3475);
FORCEPROP 0 LAST CDS_SEC 1
J 0
(-5075 3475);
PAINT MONO (-5075 3475);
DISPLAY INVISIBLE (-5075 3475);
FORCEPROP 1 LAST PATH I50
J 2
(-5075 3475);
DISPLAY 0.978723 (-5075 3475);
PAINT WHITE (-5075 3475);
DISPLAY INVISIBLE (-5075 3475);
FORCEADD CAP..1
R 2
(-4825 3025);
FORCEPROP 1 LAST PART_NUMBER A36096-155
J 2
(-4875 2875);
DISPLAY 0.617021 (-4875 2875);
PAINT BLUE (-4875 2875);
FORCEPROP 1 LAST TOLERANCE 10%
J 2
(-4875 2975);
DISPLAY 0.617021 (-4875 2975);
PAINT SKYBLUE (-4875 2975);
FORCEPROP 1 LAST MATERIAL X7R
J 2
(-4875 2925);
DISPLAY 0.617021 (-4875 2925);
PAINT SKYBLUE (-4875 2925);
FORCEPROP 1 LAST VOLTAGE 16V
J 2
(-4875 3025);
DISPLAY 0.617021 (-4875 3025);
PAINT SKYBLUE (-4875 3025);
FORCEPROP 1 LAST VALUE 0.22UF
J 2
(-4875 3075);
DISPLAY 0.617021 (-4875 3075);
PAINT SKYBLUE (-4875 3075);
FORCEPROP 1 LAST $LOCATION C844
J 2
(-4875 3125);
DISPLAY 0.617021 (-4875 3125);
PAINT AQUA (-4875 3125);
FORCEPROP 1 LAST PACK_TYPE 0402
J 2
(-4875 2825);
DISPLAY 0.617021 (-4875 2825);
PAINT SKYBLUE (-4875 2825);
FORCEPROP 2 LAST CDS_LIB mstr_discrete
J 0
(-4825 3025);
PAINT MONO (-4825 3025);
DISPLAY INVISIBLE (-4825 3025);
FORCEPROP 2 LAST ROOM OCP_STEERING
J 2
(-4825 3025);
PAINT MONO (-4825 3025);
DISPLAY INVISIBLE (-4825 3025);
FORCEPROP 1 LASTPIN (-4825 2925) $PN 2
J 2
(-4835 2905);
DISPLAY 0.787234 (-4835 2905);
PAINT ORANGE (-4835 2905);
DISPLAY INVISIBLE (-4835 2905);
FORCEPROP 1 LASTPIN (-4825 3125) $PN 1
J 2
(-4835 3105);
DISPLAY 0.787234 (-4835 3105);
PAINT ORANGE (-4835 3105);
DISPLAY INVISIBLE (-4835 3105);
FORCEPROP 2 LAST CDS_LOCATION C844
J 2
(-4875 3125);
DISPLAY 0.617021 (-4875 3125);
PAINT AQUA (-4875 3125);
DISPLAY INVISIBLE (-4875 3125);
FORCEPROP 0 LAST $SEC 1
J 0
(-4875 3175);
PAINT MONO (-4875 3175);
DISPLAY INVISIBLE (-4875 3175);
FORCEPROP 0 LAST CDS_SEC 1
J 0
(-4875 3175);
PAINT MONO (-4875 3175);
DISPLAY INVISIBLE (-4875 3175);
FORCEPROP 1 LAST PATH I51
J 2
(-4875 3175);
DISPLAY 0.978723 (-4875 3175);
PAINT WHITE (-4875 3175);
DISPLAY INVISIBLE (-4875 3175);
FORCEADD CAP..1
R 2
(-4625 3300);
FORCEPROP 1 LAST MATERIAL X7R
J 2
(-4675 3200);
DISPLAY 0.617021 (-4675 3200);
PAINT SKYBLUE (-4675 3200);
FORCEPROP 1 LAST TOLERANCE 10%
J 2
(-4675 3250);
DISPLAY 0.617021 (-4675 3250);
PAINT SKYBLUE (-4675 3250);
FORCEPROP 1 LAST $LOCATION C842
J 2
(-4675 3400);
DISPLAY 0.617021 (-4675 3400);
PAINT AQUA (-4675 3400);
FORCEPROP 1 LAST VOLTAGE 16V
J 2
(-4675 3300);
DISPLAY 0.617021 (-4675 3300);
PAINT SKYBLUE (-4675 3300);
FORCEPROP 1 LAST VALUE 0.22UF
J 2
(-4675 3350);
DISPLAY 0.617021 (-4675 3350);
PAINT SKYBLUE (-4675 3350);
FORCEPROP 1 LAST PACK_TYPE 0402
J 2
(-4675 3100);
DISPLAY 0.617021 (-4675 3100);
PAINT SKYBLUE (-4675 3100);
FORCEPROP 1 LAST PART_NUMBER A36096-155
J 2
(-4675 3150);
DISPLAY 0.617021 (-4675 3150);
PAINT BLUE (-4675 3150);
FORCEPROP 2 LAST CDS_LIB mstr_discrete
J 0
(-4625 3300);
PAINT MONO (-4625 3300);
DISPLAY INVISIBLE (-4625 3300);
FORCEPROP 2 LAST ROOM OCP_STEERING
J 2
(-4625 3300);
PAINT MONO (-4625 3300);
DISPLAY INVISIBLE (-4625 3300);
FORCEPROP 1 LASTPIN (-4625 3200) $PN 2
J 2
(-4635 3180);
DISPLAY 0.787234 (-4635 3180);
PAINT ORANGE (-4635 3180);
DISPLAY INVISIBLE (-4635 3180);
FORCEPROP 1 LASTPIN (-4625 3400) $PN 1
J 2
(-4635 3380);
DISPLAY 0.787234 (-4635 3380);
PAINT ORANGE (-4635 3380);
DISPLAY INVISIBLE (-4635 3380);
FORCEPROP 2 LAST CDS_LOCATION C842
J 2
(-4675 3400);
DISPLAY 0.617021 (-4675 3400);
PAINT AQUA (-4675 3400);
DISPLAY INVISIBLE (-4675 3400);
FORCEPROP 0 LAST $SEC 1
J 0
(-4675 3450);
PAINT MONO (-4675 3450);
DISPLAY INVISIBLE (-4675 3450);
FORCEPROP 0 LAST CDS_SEC 1
J 0
(-4675 3450);
PAINT MONO (-4675 3450);
DISPLAY INVISIBLE (-4675 3450);
FORCEPROP 1 LAST PATH I52
J 2
(-4675 3450);
DISPLAY 0.978723 (-4675 3450);
PAINT WHITE (-4675 3450);
DISPLAY INVISIBLE (-4675 3450);
FORCEADD TAP..3
(-5025 3575);
FORCEPROP 3 LASTPIN (-5025 3525) SIG_NAME P3E_CPU0_PE1_PCH_TXN<10>
J 0
(-5015 3535);
DISPLAY 0.659574 (-5015 3535);
PAINT MONO (-5015 3535);
DISPLAY INVISIBLE (-5015 3535);
FORCEPROP 1 LASTPIN (-5025 3525) BN 10
R 1
J 0
(-5032 3513);
DISPLAY 0.680851 (-5032 3513);
PAINT GREEN (-5032 3513);
FORCEPROP 1 LAST HDL_TAP TRUE
J 0
(-4705 3445);
DISPLAY 2.276596 (-4705 3445);
PAINT GREEN (-4705 3445);
DISPLAY INVISIBLE (-4705 3445);
FORCEPROP 1 LAST BODY_TYPE PLUMBING
J 0
(-4975 3525);
DISPLAY 2.276596 (-4975 3525);
PAINT GREEN (-4975 3525);
DISPLAY INVISIBLE (-4975 3525);
FORCEPROP 2 LAST CDS_LIB mstr_standard
J 0
(-5025 3575);
PAINT MONO (-5025 3575);
DISPLAY INVISIBLE (-5025 3575);
FORCEPROP 1 LAST PATH I53
J 0
(-5027 3575);
DISPLAY 0.872340 (-5027 3575);
PAINT GREEN (-5027 3575);
DISPLAY INVISIBLE (-5027 3575);
FORCEADD TAP..3
(-4825 3575);
FORCEPROP 3 LASTPIN (-4825 3525) SIG_NAME P3E_CPU0_PE1_PCH_TXN<9>
J 0
(-4815 3535);
DISPLAY 0.659574 (-4815 3535);
PAINT MONO (-4815 3535);
DISPLAY INVISIBLE (-4815 3535);
FORCEPROP 1 LASTPIN (-4825 3525) BN 9
R 1
J 0
(-4832 3513);
DISPLAY 0.680851 (-4832 3513);
PAINT GREEN (-4832 3513);
FORCEPROP 1 LAST HDL_TAP TRUE
J 0
(-4505 3445);
DISPLAY 2.276596 (-4505 3445);
PAINT GREEN (-4505 3445);
DISPLAY INVISIBLE (-4505 3445);
FORCEPROP 1 LAST BODY_TYPE PLUMBING
J 0
(-4775 3525);
DISPLAY 2.276596 (-4775 3525);
PAINT GREEN (-4775 3525);
DISPLAY INVISIBLE (-4775 3525);
FORCEPROP 2 LAST CDS_LIB mstr_standard
J 0
(-4825 3575);
PAINT MONO (-4825 3575);
DISPLAY INVISIBLE (-4825 3575);
FORCEPROP 1 LAST PATH I54
J 0
(-4827 3575);
DISPLAY 0.872340 (-4827 3575);
PAINT GREEN (-4827 3575);
DISPLAY INVISIBLE (-4827 3575);
FORCEADD TAP..3
(-4625 3575);
FORCEPROP 3 LASTPIN (-4625 3525) SIG_NAME P3E_CPU0_PE1_PCH_TXN<8>
J 0
(-4615 3535);
DISPLAY 0.659574 (-4615 3535);
PAINT MONO (-4615 3535);
DISPLAY INVISIBLE (-4615 3535);
FORCEPROP 1 LASTPIN (-4625 3525) BN 8
R 1
J 0
(-4632 3513);
DISPLAY 0.680851 (-4632 3513);
PAINT GREEN (-4632 3513);
FORCEPROP 1 LAST HDL_TAP TRUE
J 0
(-4305 3445);
DISPLAY 2.276596 (-4305 3445);
PAINT GREEN (-4305 3445);
DISPLAY INVISIBLE (-4305 3445);
FORCEPROP 1 LAST BODY_TYPE PLUMBING
J 0
(-4575 3525);
DISPLAY 2.276596 (-4575 3525);
PAINT GREEN (-4575 3525);
DISPLAY INVISIBLE (-4575 3525);
FORCEPROP 2 LAST CDS_LIB mstr_standard
J 0
(-4625 3575);
PAINT MONO (-4625 3575);
DISPLAY INVISIBLE (-4625 3575);
FORCEPROP 1 LAST PATH I55
J 0
(-4627 3575);
DISPLAY 0.872340 (-4627 3575);
PAINT GREEN (-4627 3575);
DISPLAY INVISIBLE (-4627 3575);
FORCEADD OFFPAGE..1
(-3600 2325);
FORCEPROP 2 LAST $XR0 105 
J 0
(-3852 2325);
DISPLAY 0.638298 (-3852 2325);
PAINT MONO (-3852 2325);
FORCEPROP 2 LAST $XR1 30 
J 0
(-3942 2325);
DISPLAY 0.638298 (-3942 2325);
PAINT MONO (-3942 2325);
FORCEPROP 1 LAST COMMENT_BODY TRUE
J 0
(-3480 2225);
DISPLAY 2.276596 (-3480 2225);
PAINT GREEN (-3480 2225);
DISPLAY INVISIBLE (-3480 2225);
FORCEPROP 1 LAST OFFPAGE TRUE
J 0
(-3280 2195);
PAINT GREEN (-3280 2195);
DISPLAY INVISIBLE (-3280 2195);
FORCEPROP 2 LAST CDS_LIB mstr_standard
J 0
(-3600 2325);
PAINT MONO (-3600 2325);
DISPLAY INVISIBLE (-3600 2325);
FORCEPROP 2 LAST PATH I56
J 0
(-3850 2375);
DISPLAY 1.021277 (-3850 2375);
PAINT ORANGE (-3850 2375);
DISPLAY INVISIBLE (-3850 2375);
FORCEADD TAP..3
(-3425 2275);
FORCEPROP 3 LASTPIN (-3425 2225) SIG_NAME P3E_CPU0_PE1_PCH_RXP<15>
J 0
(-3415 2235);
DISPLAY 0.659574 (-3415 2235);
PAINT MONO (-3415 2235);
DISPLAY INVISIBLE (-3415 2235);
FORCEPROP 1 LASTPIN (-3425 2225) BN 15
R 1
J 0
(-3432 2213);
DISPLAY 0.680851 (-3432 2213);
PAINT GREEN (-3432 2213);
FORCEPROP 1 LAST HDL_TAP TRUE
J 0
(-3105 2145);
DISPLAY 2.276596 (-3105 2145);
PAINT GREEN (-3105 2145);
DISPLAY INVISIBLE (-3105 2145);
FORCEPROP 1 LAST BODY_TYPE PLUMBING
J 0
(-3375 2225);
DISPLAY 2.276596 (-3375 2225);
PAINT GREEN (-3375 2225);
DISPLAY INVISIBLE (-3375 2225);
FORCEPROP 2 LAST CDS_LIB mstr_standard
J 0
(-3425 2275);
PAINT MONO (-3425 2275);
DISPLAY INVISIBLE (-3425 2275);
FORCEPROP 1 LAST PATH I57
J 0
(-3427 2275);
DISPLAY 0.872340 (-3427 2275);
PAINT GREEN (-3427 2275);
DISPLAY INVISIBLE (-3427 2275);
FORCEADD RES..2
(-3225 2025);
FORCEPROP 1 LAST $LOCATION R769
J 0
(-3180 2150);
DISPLAY 0.617021 (-3180 2150);
PAINT AQUA (-3180 2150);
FORCEPROP 1 LAST PACK_TYPE 0402
J 0
(-3185 1850);
DISPLAY 0.617021 (-3185 1850);
PAINT SKYBLUE (-3185 1850);
FORCEPROP 1 LAST PART_NUMBER G21497-005
J 0
(-3185 1900);
DISPLAY 0.617021 (-3185 1900);
PAINT BLUE (-3185 1900);
FORCEPROP 1 LAST MATERIAL CHIP
J 0
(-3185 1950);
DISPLAY 0.617021 (-3185 1950);
PAINT SKYBLUE (-3185 1950);
FORCEPROP 1 LAST WATTAGE 1/16W
J 0
(-3185 2000);
DISPLAY 0.617021 (-3185 2000);
PAINT SKYBLUE (-3185 2000);
FORCEPROP 1 LAST TOLERANCE 5%
J 0
(-3180 2050);
DISPLAY 0.617021 (-3180 2050);
PAINT SKYBLUE (-3180 2050);
FORCEPROP 1 LAST VALUE 0.0
J 0
(-3180 2100);
DISPLAY 0.617021 (-3180 2100);
PAINT SKYBLUE (-3180 2100);
FORCEPROP 2 LAST ROOM PCIE_STEERING
J 0
(-3175 2200);
PAINT MONO (-3175 2200);
DISPLAY INVISIBLE (-3175 2200);
FORCEPROP 2 LAST CDS_LIB mstr_discrete
J 0
(-3225 2025);
PAINT MONO (-3225 2025);
DISPLAY INVISIBLE (-3225 2025);
FORCEPROP 1 LASTPIN (-3225 1925) $PN 2
J 0
(-3220 1935);
DISPLAY 0.787234 (-3220 1935);
PAINT ORANGE (-3220 1935);
DISPLAY INVISIBLE (-3220 1935);
FORCEPROP 1 LASTPIN (-3225 2125) $PN 1
J 0
(-3220 2087);
DISPLAY 0.787234 (-3220 2087);
PAINT ORANGE (-3220 2087);
DISPLAY INVISIBLE (-3220 2087);
FORCEPROP 0 LAST CDS_LOCATION R769
J 0
(-3175 2200);
PAINT MONO (-3175 2200);
DISPLAY INVISIBLE (-3175 2200);
FORCEPROP 0 LAST $SEC 1
J 0
(-3175 2200);
PAINT MONO (-3175 2200);
DISPLAY INVISIBLE (-3175 2200);
FORCEPROP 0 LAST CDS_SEC 1
J 0
(-3175 2200);
PAINT MONO (-3175 2200);
DISPLAY INVISIBLE (-3175 2200);
FORCEPROP 1 LAST PATH I58
J 0
(-3175 2200);
DISPLAY 0.978723 (-3175 2200);
PAINT WHITE (-3175 2200);
DISPLAY INVISIBLE (-3175 2200);
FORCEADD TAP..3
(-3225 2275);
FORCEPROP 3 LASTPIN (-3225 2225) SIG_NAME P3E_CPU0_PE1_PCH_RXP<14>
J 0
(-3215 2235);
DISPLAY 0.659574 (-3215 2235);
PAINT MONO (-3215 2235);
DISPLAY INVISIBLE (-3215 2235);
FORCEPROP 1 LASTPIN (-3225 2225) BN 14
R 1
J 0
(-3232 2213);
DISPLAY 0.680851 (-3232 2213);
PAINT GREEN (-3232 2213);
FORCEPROP 1 LAST HDL_TAP TRUE
J 0
(-2905 2145);
DISPLAY 2.276596 (-2905 2145);
PAINT GREEN (-2905 2145);
DISPLAY INVISIBLE (-2905 2145);
FORCEPROP 1 LAST BODY_TYPE PLUMBING
J 0
(-3175 2225);
DISPLAY 2.276596 (-3175 2225);
PAINT GREEN (-3175 2225);
DISPLAY INVISIBLE (-3175 2225);
FORCEPROP 2 LAST CDS_LIB mstr_standard
J 0
(-3225 2275);
PAINT MONO (-3225 2275);
DISPLAY INVISIBLE (-3225 2275);
FORCEPROP 1 LAST PATH I59
J 0
(-3227 2275);
DISPLAY 0.872340 (-3227 2275);
PAINT GREEN (-3227 2275);
DISPLAY INVISIBLE (-3227 2275);
FORCEADD TAP..7
(-5325 1475);
FORCEPROP 3 LASTPIN (-5325 1525) SIG_NAME P3E_CPU0_PE1_PCH_CON_TXP<12>
J 0
(-5315 1535);
DISPLAY 0.659574 (-5315 1535);
PAINT MONO (-5315 1535);
DISPLAY INVISIBLE (-5315 1535);
FORCEPROP 1 LASTPIN (-5325 1525) BN 12
R 1
J 0
(-5332 1473);
DISPLAY 0.680851 (-5332 1473);
PAINT GREEN (-5332 1473);
FORCEPROP 1 LAST HDL_TAP TRUE
J 0
(-5005 1345);
DISPLAY 2.276596 (-5005 1345);
PAINT GREEN (-5005 1345);
DISPLAY INVISIBLE (-5005 1345);
FORCEPROP 1 LAST BODY_TYPE PLUMBING
J 0
(-5275 1475);
DISPLAY 2.276596 (-5275 1475);
PAINT GREEN (-5275 1475);
DISPLAY INVISIBLE (-5275 1475);
FORCEPROP 2 LAST CDS_LIB mstr_standard
J 0
(-5325 1475);
PAINT MONO (-5325 1475);
DISPLAY INVISIBLE (-5325 1475);
FORCEPROP 1 LAST PATH I6
J 0
(-5327 1475);
DISPLAY 0.872340 (-5327 1475);
PAINT GREEN (-5327 1475);
DISPLAY INVISIBLE (-5327 1475);
FORCEADD TAP..7
(-3500 2775);
FORCEPROP 3 LASTPIN (-3500 2825) SIG_NAME P3E_CPU0_PE1_PCH_CON_RXN<15>
J 0
(-3490 2835);
DISPLAY 0.659574 (-3490 2835);
PAINT MONO (-3490 2835);
DISPLAY INVISIBLE (-3490 2835);
FORCEPROP 1 LASTPIN (-3500 2825) BN 15
R 1
J 0
(-3507 2773);
DISPLAY 0.680851 (-3507 2773);
PAINT GREEN (-3507 2773);
FORCEPROP 1 LAST HDL_TAP TRUE
J 0
(-3180 2645);
DISPLAY 2.276596 (-3180 2645);
PAINT GREEN (-3180 2645);
DISPLAY INVISIBLE (-3180 2645);
FORCEPROP 1 LAST BODY_TYPE PLUMBING
J 0
(-3450 2775);
DISPLAY 2.276596 (-3450 2775);
PAINT GREEN (-3450 2775);
DISPLAY INVISIBLE (-3450 2775);
FORCEPROP 2 LAST CDS_LIB mstr_standard
J 0
(-3500 2775);
PAINT MONO (-3500 2775);
DISPLAY INVISIBLE (-3500 2775);
FORCEPROP 1 LAST PATH I60
J 0
(-3502 2775);
DISPLAY 0.872340 (-3502 2775);
PAINT GREEN (-3502 2775);
DISPLAY INVISIBLE (-3502 2775);
FORCEADD TAP..7
(-3300 2775);
FORCEPROP 3 LASTPIN (-3300 2825) SIG_NAME P3E_CPU0_PE1_PCH_CON_RXN<14>
J 0
(-3290 2835);
DISPLAY 0.659574 (-3290 2835);
PAINT MONO (-3290 2835);
DISPLAY INVISIBLE (-3290 2835);
FORCEPROP 1 LASTPIN (-3300 2825) BN 14
R 1
J 0
(-3307 2773);
DISPLAY 0.680851 (-3307 2773);
PAINT GREEN (-3307 2773);
FORCEPROP 1 LAST HDL_TAP TRUE
J 0
(-2980 2645);
DISPLAY 2.276596 (-2980 2645);
PAINT GREEN (-2980 2645);
DISPLAY INVISIBLE (-2980 2645);
FORCEPROP 1 LAST BODY_TYPE PLUMBING
J 0
(-3250 2775);
DISPLAY 2.276596 (-3250 2775);
PAINT GREEN (-3250 2775);
DISPLAY INVISIBLE (-3250 2775);
FORCEPROP 2 LAST CDS_LIB mstr_standard
J 0
(-3300 2775);
PAINT MONO (-3300 2775);
DISPLAY INVISIBLE (-3300 2775);
FORCEPROP 1 LAST PATH I61
J 0
(-3302 2775);
DISPLAY 0.872340 (-3302 2775);
PAINT GREEN (-3302 2775);
DISPLAY INVISIBLE (-3302 2775);
FORCEADD TAP..7
(-3100 2775);
FORCEPROP 3 LASTPIN (-3100 2825) SIG_NAME P3E_CPU0_PE1_PCH_CON_RXN<13>
J 0
(-3090 2835);
DISPLAY 0.659574 (-3090 2835);
PAINT MONO (-3090 2835);
DISPLAY INVISIBLE (-3090 2835);
FORCEPROP 1 LASTPIN (-3100 2825) BN 13
R 1
J 0
(-3107 2773);
DISPLAY 0.680851 (-3107 2773);
PAINT GREEN (-3107 2773);
FORCEPROP 1 LAST HDL_TAP TRUE
J 0
(-2780 2645);
DISPLAY 2.276596 (-2780 2645);
PAINT GREEN (-2780 2645);
DISPLAY INVISIBLE (-2780 2645);
FORCEPROP 1 LAST BODY_TYPE PLUMBING
J 0
(-3050 2775);
DISPLAY 2.276596 (-3050 2775);
PAINT GREEN (-3050 2775);
DISPLAY INVISIBLE (-3050 2775);
FORCEPROP 2 LAST CDS_LIB mstr_standard
J 0
(-3100 2775);
PAINT MONO (-3100 2775);
DISPLAY INVISIBLE (-3100 2775);
FORCEPROP 1 LAST PATH I62
J 0
(-3102 2775);
DISPLAY 0.872340 (-3102 2775);
PAINT GREEN (-3102 2775);
DISPLAY INVISIBLE (-3102 2775);
FORCEADD OFFPAGE..1
(-3675 3625);
FORCEPROP 2 LAST $XR0 105 
J 0
(-3927 3625);
DISPLAY 0.638298 (-3927 3625);
PAINT MONO (-3927 3625);
FORCEPROP 2 LAST $XR1 30 
J 0
(-4017 3625);
DISPLAY 0.638298 (-4017 3625);
PAINT MONO (-4017 3625);
FORCEPROP 1 LAST COMMENT_BODY TRUE
J 0
(-3555 3525);
DISPLAY 2.276596 (-3555 3525);
PAINT GREEN (-3555 3525);
DISPLAY INVISIBLE (-3555 3525);
FORCEPROP 1 LAST OFFPAGE TRUE
J 0
(-3355 3495);
PAINT GREEN (-3355 3495);
DISPLAY INVISIBLE (-3355 3495);
FORCEPROP 2 LAST CDS_LIB mstr_standard
J 0
(-3675 3625);
PAINT MONO (-3675 3625);
DISPLAY INVISIBLE (-3675 3625);
FORCEPROP 2 LAST PATH I63
J 0
(-3925 3675);
DISPLAY 1.021277 (-3925 3675);
PAINT ORANGE (-3925 3675);
DISPLAY INVISIBLE (-3925 3675);
FORCEADD RES..2
(-3500 3025);
FORCEPROP 1 LAST PACK_TYPE 0402
J 0
(-3460 2850);
DISPLAY 0.617021 (-3460 2850);
PAINT SKYBLUE (-3460 2850);
FORCEPROP 1 LAST PART_NUMBER G21497-005
J 0
(-3460 2900);
DISPLAY 0.617021 (-3460 2900);
PAINT BLUE (-3460 2900);
FORCEPROP 1 LAST WATTAGE 1/16W
J 0
(-3460 3000);
DISPLAY 0.617021 (-3460 3000);
PAINT SKYBLUE (-3460 3000);
FORCEPROP 1 LAST VALUE 0.0
J 0
(-3455 3100);
DISPLAY 0.617021 (-3455 3100);
PAINT SKYBLUE (-3455 3100);
FORCEPROP 1 LAST TOLERANCE 5%
J 0
(-3455 3050);
DISPLAY 0.617021 (-3455 3050);
PAINT SKYBLUE (-3455 3050);
FORCEPROP 1 LAST $LOCATION R760
J 0
(-3455 3150);
DISPLAY 0.617021 (-3455 3150);
PAINT AQUA (-3455 3150);
FORCEPROP 1 LAST MATERIAL CHIP
J 0
(-3460 2950);
DISPLAY 0.617021 (-3460 2950);
PAINT SKYBLUE (-3460 2950);
FORCEPROP 2 LAST ROOM PCIE_STEERING
J 0
(-3450 3200);
PAINT MONO (-3450 3200);
DISPLAY INVISIBLE (-3450 3200);
FORCEPROP 2 LAST CDS_LIB mstr_discrete
J 0
(-3500 3025);
PAINT MONO (-3500 3025);
DISPLAY INVISIBLE (-3500 3025);
FORCEPROP 1 LASTPIN (-3500 2925) $PN 2
J 0
(-3495 2935);
DISPLAY 0.787234 (-3495 2935);
PAINT ORANGE (-3495 2935);
DISPLAY INVISIBLE (-3495 2935);
FORCEPROP 1 LASTPIN (-3500 3125) $PN 1
J 0
(-3495 3087);
DISPLAY 0.787234 (-3495 3087);
PAINT ORANGE (-3495 3087);
DISPLAY INVISIBLE (-3495 3087);
FORCEPROP 0 LAST CDS_LOCATION R760
J 0
(-3450 3200);
PAINT MONO (-3450 3200);
DISPLAY INVISIBLE (-3450 3200);
FORCEPROP 0 LAST $SEC 1
J 0
(-3450 3200);
PAINT MONO (-3450 3200);
DISPLAY INVISIBLE (-3450 3200);
FORCEPROP 0 LAST CDS_SEC 1
J 0
(-3450 3200);
PAINT MONO (-3450 3200);
DISPLAY INVISIBLE (-3450 3200);
FORCEPROP 1 LAST PATH I64
J 0
(-3450 3200);
DISPLAY 0.978723 (-3450 3200);
PAINT WHITE (-3450 3200);
DISPLAY INVISIBLE (-3450 3200);
FORCEADD RES..2
(-3100 3025);
FORCEPROP 1 LAST $LOCATION R771
J 0
(-3055 3150);
DISPLAY 0.617021 (-3055 3150);
PAINT AQUA (-3055 3150);
FORCEPROP 1 LAST PACK_TYPE 0402
J 0
(-3060 2850);
DISPLAY 0.617021 (-3060 2850);
PAINT SKYBLUE (-3060 2850);
FORCEPROP 1 LAST TOLERANCE 5%
J 0
(-3055 3050);
DISPLAY 0.617021 (-3055 3050);
PAINT SKYBLUE (-3055 3050);
FORCEPROP 1 LAST WATTAGE 1/16W
J 0
(-3060 3000);
DISPLAY 0.617021 (-3060 3000);
PAINT SKYBLUE (-3060 3000);
FORCEPROP 1 LAST MATERIAL CHIP
J 0
(-3060 2950);
DISPLAY 0.617021 (-3060 2950);
PAINT SKYBLUE (-3060 2950);
FORCEPROP 1 LAST VALUE 0.0
J 0
(-3055 3100);
DISPLAY 0.617021 (-3055 3100);
PAINT SKYBLUE (-3055 3100);
FORCEPROP 1 LAST PART_NUMBER G21497-005
J 0
(-3060 2900);
DISPLAY 0.617021 (-3060 2900);
PAINT BLUE (-3060 2900);
FORCEPROP 2 LAST ROOM PCIE_STEERING
J 0
(-3050 3200);
PAINT MONO (-3050 3200);
DISPLAY INVISIBLE (-3050 3200);
FORCEPROP 2 LAST CDS_LIB mstr_discrete
J 0
(-3100 3025);
PAINT MONO (-3100 3025);
DISPLAY INVISIBLE (-3100 3025);
FORCEPROP 1 LASTPIN (-3100 2925) $PN 2
J 0
(-3095 2935);
DISPLAY 0.787234 (-3095 2935);
PAINT ORANGE (-3095 2935);
DISPLAY INVISIBLE (-3095 2935);
FORCEPROP 1 LASTPIN (-3100 3125) $PN 1
J 0
(-3095 3087);
DISPLAY 0.787234 (-3095 3087);
PAINT ORANGE (-3095 3087);
DISPLAY INVISIBLE (-3095 3087);
FORCEPROP 0 LAST CDS_LOCATION R771
J 0
(-3050 3200);
PAINT MONO (-3050 3200);
DISPLAY INVISIBLE (-3050 3200);
FORCEPROP 0 LAST $SEC 1
J 0
(-3050 3200);
PAINT MONO (-3050 3200);
DISPLAY INVISIBLE (-3050 3200);
FORCEPROP 0 LAST CDS_SEC 1
J 0
(-3050 3200);
PAINT MONO (-3050 3200);
DISPLAY INVISIBLE (-3050 3200);
FORCEPROP 1 LAST PATH I65
J 0
(-3050 3200);
DISPLAY 0.978723 (-3050 3200);
PAINT WHITE (-3050 3200);
DISPLAY INVISIBLE (-3050 3200);
FORCEADD RES..2
(-3300 3325);
FORCEPROP 1 LAST $LOCATION R768
J 0
(-3255 3450);
DISPLAY 0.617021 (-3255 3450);
PAINT AQUA (-3255 3450);
FORCEPROP 1 LAST VALUE 0.0
J 0
(-3255 3400);
DISPLAY 0.617021 (-3255 3400);
PAINT SKYBLUE (-3255 3400);
FORCEPROP 1 LAST WATTAGE 1/16W
J 0
(-3260 3300);
DISPLAY 0.617021 (-3260 3300);
PAINT SKYBLUE (-3260 3300);
FORCEPROP 1 LAST PART_NUMBER G21497-005
J 0
(-3260 3200);
DISPLAY 0.617021 (-3260 3200);
PAINT BLUE (-3260 3200);
FORCEPROP 1 LAST TOLERANCE 5%
J 0
(-3255 3350);
DISPLAY 0.617021 (-3255 3350);
PAINT SKYBLUE (-3255 3350);
FORCEPROP 1 LAST MATERIAL CHIP
J 0
(-3260 3250);
DISPLAY 0.617021 (-3260 3250);
PAINT SKYBLUE (-3260 3250);
FORCEPROP 1 LAST PACK_TYPE 0402
J 0
(-3260 3150);
DISPLAY 0.617021 (-3260 3150);
PAINT SKYBLUE (-3260 3150);
FORCEPROP 2 LAST ROOM PCIE_STEERING
J 0
(-3250 3500);
PAINT MONO (-3250 3500);
DISPLAY INVISIBLE (-3250 3500);
FORCEPROP 2 LAST CDS_LIB mstr_discrete
J 0
(-3300 3325);
PAINT MONO (-3300 3325);
DISPLAY INVISIBLE (-3300 3325);
FORCEPROP 1 LASTPIN (-3300 3225) $PN 2
J 0
(-3295 3235);
DISPLAY 0.787234 (-3295 3235);
PAINT ORANGE (-3295 3235);
DISPLAY INVISIBLE (-3295 3235);
FORCEPROP 1 LASTPIN (-3300 3425) $PN 1
J 0
(-3295 3387);
DISPLAY 0.787234 (-3295 3387);
PAINT ORANGE (-3295 3387);
DISPLAY INVISIBLE (-3295 3387);
FORCEPROP 0 LAST CDS_LOCATION R768
J 0
(-3250 3500);
PAINT MONO (-3250 3500);
DISPLAY INVISIBLE (-3250 3500);
FORCEPROP 0 LAST $SEC 1
J 0
(-3250 3500);
PAINT MONO (-3250 3500);
DISPLAY INVISIBLE (-3250 3500);
FORCEPROP 0 LAST CDS_SEC 1
J 0
(-3250 3500);
PAINT MONO (-3250 3500);
DISPLAY INVISIBLE (-3250 3500);
FORCEPROP 1 LAST PATH I66
J 0
(-3250 3500);
DISPLAY 0.978723 (-3250 3500);
PAINT WHITE (-3250 3500);
DISPLAY INVISIBLE (-3250 3500);
FORCEADD TAP..3
(-3500 3575);
FORCEPROP 3 LASTPIN (-3500 3525) SIG_NAME P3E_CPU0_PE1_PCH_RXN<15>
J 0
(-3490 3535);
DISPLAY 0.659574 (-3490 3535);
PAINT MONO (-3490 3535);
DISPLAY INVISIBLE (-3490 3535);
FORCEPROP 1 LASTPIN (-3500 3525) BN 15
R 1
J 0
(-3507 3513);
DISPLAY 0.680851 (-3507 3513);
PAINT GREEN (-3507 3513);
FORCEPROP 1 LAST HDL_TAP TRUE
J 0
(-3180 3445);
DISPLAY 2.276596 (-3180 3445);
PAINT GREEN (-3180 3445);
DISPLAY INVISIBLE (-3180 3445);
FORCEPROP 1 LAST BODY_TYPE PLUMBING
J 0
(-3450 3525);
DISPLAY 2.276596 (-3450 3525);
PAINT GREEN (-3450 3525);
DISPLAY INVISIBLE (-3450 3525);
FORCEPROP 2 LAST CDS_LIB mstr_standard
J 0
(-3500 3575);
PAINT MONO (-3500 3575);
DISPLAY INVISIBLE (-3500 3575);
FORCEPROP 1 LAST PATH I67
J 0
(-3502 3575);
DISPLAY 0.872340 (-3502 3575);
PAINT GREEN (-3502 3575);
DISPLAY INVISIBLE (-3502 3575);
FORCEADD TAP..3
(-3300 3575);
FORCEPROP 3 LASTPIN (-3300 3525) SIG_NAME P3E_CPU0_PE1_PCH_RXN<14>
J 0
(-3290 3535);
DISPLAY 0.659574 (-3290 3535);
PAINT MONO (-3290 3535);
DISPLAY INVISIBLE (-3290 3535);
FORCEPROP 1 LASTPIN (-3300 3525) BN 14
R 1
J 0
(-3307 3513);
DISPLAY 0.680851 (-3307 3513);
PAINT GREEN (-3307 3513);
FORCEPROP 1 LAST HDL_TAP TRUE
J 0
(-2980 3445);
DISPLAY 2.276596 (-2980 3445);
PAINT GREEN (-2980 3445);
DISPLAY INVISIBLE (-2980 3445);
FORCEPROP 1 LAST BODY_TYPE PLUMBING
J 0
(-3250 3525);
DISPLAY 2.276596 (-3250 3525);
PAINT GREEN (-3250 3525);
DISPLAY INVISIBLE (-3250 3525);
FORCEPROP 2 LAST CDS_LIB mstr_standard
J 0
(-3300 3575);
PAINT MONO (-3300 3575);
DISPLAY INVISIBLE (-3300 3575);
FORCEPROP 1 LAST PATH I68
J 0
(-3302 3575);
DISPLAY 0.872340 (-3302 3575);
PAINT GREEN (-3302 3575);
DISPLAY INVISIBLE (-3302 3575);
FORCEADD TAP..3
(-3100 3575);
FORCEPROP 3 LASTPIN (-3100 3525) SIG_NAME P3E_CPU0_PE1_PCH_RXN<13>
J 0
(-3090 3535);
DISPLAY 0.659574 (-3090 3535);
PAINT MONO (-3090 3535);
DISPLAY INVISIBLE (-3090 3535);
FORCEPROP 1 LASTPIN (-3100 3525) BN 13
R 1
J 0
(-3107 3513);
DISPLAY 0.680851 (-3107 3513);
PAINT GREEN (-3107 3513);
FORCEPROP 1 LAST HDL_TAP TRUE
J 0
(-2780 3445);
DISPLAY 2.276596 (-2780 3445);
PAINT GREEN (-2780 3445);
DISPLAY INVISIBLE (-2780 3445);
FORCEPROP 1 LAST BODY_TYPE PLUMBING
J 0
(-3050 3525);
DISPLAY 2.276596 (-3050 3525);
PAINT GREEN (-3050 3525);
DISPLAY INVISIBLE (-3050 3525);
FORCEPROP 2 LAST CDS_LIB mstr_standard
J 0
(-3100 3575);
PAINT MONO (-3100 3575);
DISPLAY INVISIBLE (-3100 3575);
FORCEPROP 1 LAST PATH I69
J 0
(-3102 3575);
DISPLAY 0.872340 (-3102 3575);
PAINT GREEN (-3102 3575);
DISPLAY INVISIBLE (-3102 3575);
FORCEADD TAP..7
(-5125 1475);
FORCEPROP 3 LASTPIN (-5125 1525) SIG_NAME P3E_CPU0_PE1_PCH_CON_TXP<11>
J 0
(-5115 1535);
DISPLAY 0.659574 (-5115 1535);
PAINT MONO (-5115 1535);
DISPLAY INVISIBLE (-5115 1535);
FORCEPROP 1 LASTPIN (-5125 1525) BN 11
R 1
J 0
(-5132 1473);
DISPLAY 0.680851 (-5132 1473);
PAINT GREEN (-5132 1473);
FORCEPROP 1 LAST HDL_TAP TRUE
J 0
(-4805 1345);
DISPLAY 2.276596 (-4805 1345);
PAINT GREEN (-4805 1345);
DISPLAY INVISIBLE (-4805 1345);
FORCEPROP 1 LAST BODY_TYPE PLUMBING
J 0
(-5075 1475);
DISPLAY 2.276596 (-5075 1475);
PAINT GREEN (-5075 1475);
DISPLAY INVISIBLE (-5075 1475);
FORCEPROP 2 LAST CDS_LIB mstr_standard
J 0
(-5125 1475);
PAINT MONO (-5125 1475);
DISPLAY INVISIBLE (-5125 1475);
FORCEPROP 1 LAST PATH I7
J 0
(-5127 1475);
DISPLAY 0.872340 (-5127 1475);
PAINT GREEN (-5127 1475);
DISPLAY INVISIBLE (-5127 1475);
FORCEADD TAP..7
(-3025 1475);
FORCEPROP 3 LASTPIN (-3025 1525) SIG_NAME P3E_CPU0_PE1_PCH_CON_RXP<13>
J 0
(-3015 1535);
DISPLAY 0.659574 (-3015 1535);
PAINT MONO (-3015 1535);
DISPLAY INVISIBLE (-3015 1535);
FORCEPROP 1 LASTPIN (-3025 1525) BN 13
R 1
J 0
(-3032 1473);
DISPLAY 0.680851 (-3032 1473);
PAINT GREEN (-3032 1473);
FORCEPROP 1 LAST HDL_TAP TRUE
J 0
(-2705 1345);
DISPLAY 2.276596 (-2705 1345);
PAINT GREEN (-2705 1345);
DISPLAY INVISIBLE (-2705 1345);
FORCEPROP 1 LAST BODY_TYPE PLUMBING
J 0
(-2975 1475);
DISPLAY 2.276596 (-2975 1475);
PAINT GREEN (-2975 1475);
DISPLAY INVISIBLE (-2975 1475);
FORCEPROP 2 LAST CDS_LIB mstr_standard
J 0
(-3025 1475);
PAINT MONO (-3025 1475);
DISPLAY INVISIBLE (-3025 1475);
FORCEPROP 1 LAST PATH I70
J 0
(-3027 1475);
DISPLAY 0.872340 (-3027 1475);
PAINT GREEN (-3027 1475);
DISPLAY INVISIBLE (-3027 1475);
FORCEADD TAP..7
(-2825 1475);
FORCEPROP 3 LASTPIN (-2825 1525) SIG_NAME P3E_CPU0_PE1_PCH_CON_RXP<12>
J 0
(-2815 1535);
DISPLAY 0.659574 (-2815 1535);
PAINT MONO (-2815 1535);
DISPLAY INVISIBLE (-2815 1535);
FORCEPROP 1 LASTPIN (-2825 1525) BN 12
R 1
J 0
(-2832 1473);
DISPLAY 0.680851 (-2832 1473);
PAINT GREEN (-2832 1473);
FORCEPROP 1 LAST HDL_TAP TRUE
J 0
(-2505 1345);
DISPLAY 2.276596 (-2505 1345);
PAINT GREEN (-2505 1345);
DISPLAY INVISIBLE (-2505 1345);
FORCEPROP 1 LAST BODY_TYPE PLUMBING
J 0
(-2775 1475);
DISPLAY 2.276596 (-2775 1475);
PAINT GREEN (-2775 1475);
DISPLAY INVISIBLE (-2775 1475);
FORCEPROP 2 LAST CDS_LIB mstr_standard
J 0
(-2825 1475);
PAINT MONO (-2825 1475);
DISPLAY INVISIBLE (-2825 1475);
FORCEPROP 1 LAST PATH I71
J 0
(-2827 1475);
DISPLAY 0.872340 (-2827 1475);
PAINT GREEN (-2827 1475);
DISPLAY INVISIBLE (-2827 1475);
FORCEADD RES..2
(-3025 1725);
FORCEPROP 1 LAST $LOCATION R774
J 0
(-2980 1850);
DISPLAY 0.617021 (-2980 1850);
PAINT AQUA (-2980 1850);
FORCEPROP 1 LAST PACK_TYPE 0402
J 0
(-2985 1550);
DISPLAY 0.617021 (-2985 1550);
PAINT SKYBLUE (-2985 1550);
FORCEPROP 1 LAST PART_NUMBER G21497-005
J 0
(-2985 1600);
DISPLAY 0.617021 (-2985 1600);
PAINT BLUE (-2985 1600);
FORCEPROP 1 LAST MATERIAL CHIP
J 0
(-2985 1650);
DISPLAY 0.617021 (-2985 1650);
PAINT SKYBLUE (-2985 1650);
FORCEPROP 1 LAST VALUE 0.0
J 0
(-2980 1800);
DISPLAY 0.617021 (-2980 1800);
PAINT SKYBLUE (-2980 1800);
FORCEPROP 1 LAST TOLERANCE 5%
J 0
(-2980 1750);
DISPLAY 0.617021 (-2980 1750);
PAINT SKYBLUE (-2980 1750);
FORCEPROP 1 LAST WATTAGE 1/16W
J 0
(-2985 1700);
DISPLAY 0.617021 (-2985 1700);
PAINT SKYBLUE (-2985 1700);
FORCEPROP 2 LAST ROOM PCIE_STEERING
J 0
(-2975 1900);
PAINT MONO (-2975 1900);
DISPLAY INVISIBLE (-2975 1900);
FORCEPROP 2 LAST CDS_LIB mstr_discrete
J 0
(-3025 1725);
PAINT MONO (-3025 1725);
DISPLAY INVISIBLE (-3025 1725);
FORCEPROP 1 LASTPIN (-3025 1625) $PN 2
J 0
(-3020 1635);
DISPLAY 0.787234 (-3020 1635);
PAINT ORANGE (-3020 1635);
DISPLAY INVISIBLE (-3020 1635);
FORCEPROP 1 LASTPIN (-3025 1825) $PN 1
J 0
(-3020 1787);
DISPLAY 0.787234 (-3020 1787);
PAINT ORANGE (-3020 1787);
DISPLAY INVISIBLE (-3020 1787);
FORCEPROP 0 LAST CDS_LOCATION R774
J 0
(-2975 1900);
PAINT MONO (-2975 1900);
DISPLAY INVISIBLE (-2975 1900);
FORCEPROP 0 LAST $SEC 1
J 0
(-2975 1900);
PAINT MONO (-2975 1900);
DISPLAY INVISIBLE (-2975 1900);
FORCEPROP 0 LAST CDS_SEC 1
J 0
(-2975 1900);
PAINT MONO (-2975 1900);
DISPLAY INVISIBLE (-2975 1900);
FORCEPROP 1 LAST PATH I72
J 0
(-2975 1900);
DISPLAY 0.978723 (-2975 1900);
PAINT WHITE (-2975 1900);
DISPLAY INVISIBLE (-2975 1900);
FORCEADD TAP..7
(-2625 1475);
FORCEPROP 3 LASTPIN (-2625 1525) SIG_NAME P3E_CPU0_PE1_PCH_CON_RXP<11>
J 0
(-2615 1535);
DISPLAY 0.659574 (-2615 1535);
PAINT MONO (-2615 1535);
DISPLAY INVISIBLE (-2615 1535);
FORCEPROP 1 LASTPIN (-2625 1525) BN 11
R 1
J 0
(-2632 1473);
DISPLAY 0.680851 (-2632 1473);
PAINT GREEN (-2632 1473);
FORCEPROP 1 LAST HDL_TAP TRUE
J 0
(-2305 1345);
DISPLAY 2.276596 (-2305 1345);
PAINT GREEN (-2305 1345);
DISPLAY INVISIBLE (-2305 1345);
FORCEPROP 1 LAST BODY_TYPE PLUMBING
J 0
(-2575 1475);
DISPLAY 2.276596 (-2575 1475);
PAINT GREEN (-2575 1475);
DISPLAY INVISIBLE (-2575 1475);
FORCEPROP 2 LAST CDS_LIB mstr_standard
J 0
(-2625 1475);
PAINT MONO (-2625 1475);
DISPLAY INVISIBLE (-2625 1475);
FORCEPROP 1 LAST PATH I73
J 0
(-2627 1475);
DISPLAY 0.872340 (-2627 1475);
PAINT GREEN (-2627 1475);
DISPLAY INVISIBLE (-2627 1475);
FORCEADD RES..2
(-2625 1725);
FORCEPROP 1 LAST WATTAGE 1/16W
J 0
(-2585 1700);
DISPLAY 0.617021 (-2585 1700);
PAINT SKYBLUE (-2585 1700);
FORCEPROP 1 LAST MATERIAL CHIP
J 0
(-2585 1650);
DISPLAY 0.617021 (-2585 1650);
PAINT SKYBLUE (-2585 1650);
FORCEPROP 1 LAST PART_NUMBER G21497-005
J 0
(-2585 1600);
DISPLAY 0.617021 (-2585 1600);
PAINT BLUE (-2585 1600);
FORCEPROP 1 LAST PACK_TYPE 0402
J 0
(-2585 1550);
DISPLAY 0.617021 (-2585 1550);
PAINT SKYBLUE (-2585 1550);
FORCEPROP 1 LAST VALUE 0.0
J 0
(-2580 1800);
DISPLAY 0.617021 (-2580 1800);
PAINT SKYBLUE (-2580 1800);
FORCEPROP 1 LAST TOLERANCE 5%
J 0
(-2580 1750);
DISPLAY 0.617021 (-2580 1750);
PAINT SKYBLUE (-2580 1750);
FORCEPROP 1 LAST $LOCATION R779
J 0
(-2580 1850);
DISPLAY 0.617021 (-2580 1850);
PAINT AQUA (-2580 1850);
FORCEPROP 2 LAST ROOM PCIE_STEERING
J 0
(-2575 1900);
PAINT MONO (-2575 1900);
DISPLAY INVISIBLE (-2575 1900);
FORCEPROP 2 LAST CDS_LIB mstr_discrete
J 0
(-2625 1725);
PAINT MONO (-2625 1725);
DISPLAY INVISIBLE (-2625 1725);
FORCEPROP 1 LASTPIN (-2625 1625) $PN 2
J 0
(-2620 1635);
DISPLAY 0.787234 (-2620 1635);
PAINT ORANGE (-2620 1635);
DISPLAY INVISIBLE (-2620 1635);
FORCEPROP 1 LASTPIN (-2625 1825) $PN 1
J 0
(-2620 1787);
DISPLAY 0.787234 (-2620 1787);
PAINT ORANGE (-2620 1787);
DISPLAY INVISIBLE (-2620 1787);
FORCEPROP 0 LAST CDS_LOCATION R779
J 0
(-2575 1900);
PAINT MONO (-2575 1900);
DISPLAY INVISIBLE (-2575 1900);
FORCEPROP 0 LAST $SEC 1
J 0
(-2575 1900);
PAINT MONO (-2575 1900);
DISPLAY INVISIBLE (-2575 1900);
FORCEPROP 0 LAST CDS_SEC 1
J 0
(-2575 1900);
PAINT MONO (-2575 1900);
DISPLAY INVISIBLE (-2575 1900);
FORCEPROP 1 LAST PATH I74
J 0
(-2575 1900);
DISPLAY 0.978723 (-2575 1900);
PAINT WHITE (-2575 1900);
DISPLAY INVISIBLE (-2575 1900);
FORCEADD TAP..7
(-2425 1475);
FORCEPROP 3 LASTPIN (-2425 1525) SIG_NAME P3E_CPU0_PE1_PCH_CON_RXP<10>
J 0
(-2415 1535);
DISPLAY 0.659574 (-2415 1535);
PAINT MONO (-2415 1535);
DISPLAY INVISIBLE (-2415 1535);
FORCEPROP 1 LASTPIN (-2425 1525) BN 10
R 1
J 0
(-2432 1473);
DISPLAY 0.680851 (-2432 1473);
PAINT GREEN (-2432 1473);
FORCEPROP 1 LAST HDL_TAP TRUE
J 0
(-2105 1345);
DISPLAY 2.276596 (-2105 1345);
PAINT GREEN (-2105 1345);
DISPLAY INVISIBLE (-2105 1345);
FORCEPROP 1 LAST BODY_TYPE PLUMBING
J 0
(-2375 1475);
DISPLAY 2.276596 (-2375 1475);
PAINT GREEN (-2375 1475);
DISPLAY INVISIBLE (-2375 1475);
FORCEPROP 2 LAST CDS_LIB mstr_standard
J 0
(-2425 1475);
PAINT MONO (-2425 1475);
DISPLAY INVISIBLE (-2425 1475);
FORCEPROP 1 LAST PATH I75
J 0
(-2427 1475);
DISPLAY 0.872340 (-2427 1475);
PAINT GREEN (-2427 1475);
DISPLAY INVISIBLE (-2427 1475);
FORCEADD TAP..7
(-2225 1475);
FORCEPROP 3 LASTPIN (-2225 1525) SIG_NAME P3E_CPU0_PE1_PCH_CON_RXP<9>
J 0
(-2215 1535);
DISPLAY 0.659574 (-2215 1535);
PAINT MONO (-2215 1535);
DISPLAY INVISIBLE (-2215 1535);
FORCEPROP 1 LASTPIN (-2225 1525) BN 9
R 1
J 0
(-2232 1473);
DISPLAY 0.680851 (-2232 1473);
PAINT GREEN (-2232 1473);
FORCEPROP 1 LAST HDL_TAP TRUE
J 0
(-1905 1345);
DISPLAY 2.276596 (-1905 1345);
PAINT GREEN (-1905 1345);
DISPLAY INVISIBLE (-1905 1345);
FORCEPROP 1 LAST BODY_TYPE PLUMBING
J 0
(-2175 1475);
DISPLAY 2.276596 (-2175 1475);
PAINT GREEN (-2175 1475);
DISPLAY INVISIBLE (-2175 1475);
FORCEPROP 2 LAST CDS_LIB mstr_standard
J 0
(-2225 1475);
PAINT MONO (-2225 1475);
DISPLAY INVISIBLE (-2225 1475);
FORCEPROP 1 LAST PATH I76
J 0
(-2227 1475);
DISPLAY 0.872340 (-2227 1475);
PAINT GREEN (-2227 1475);
DISPLAY INVISIBLE (-2227 1475);
FORCEADD RES..2
(-2225 1725);
FORCEPROP 1 LAST $LOCATION R783
J 0
(-2180 1850);
DISPLAY 0.617021 (-2180 1850);
PAINT AQUA (-2180 1850);
FORCEPROP 1 LAST TOLERANCE 5%
J 0
(-2180 1750);
DISPLAY 0.617021 (-2180 1750);
PAINT SKYBLUE (-2180 1750);
FORCEPROP 1 LAST WATTAGE 1/16W
J 0
(-2185 1700);
DISPLAY 0.617021 (-2185 1700);
PAINT SKYBLUE (-2185 1700);
FORCEPROP 1 LAST PART_NUMBER G21497-005
J 0
(-2185 1600);
DISPLAY 0.617021 (-2185 1600);
PAINT BLUE (-2185 1600);
FORCEPROP 1 LAST MATERIAL CHIP
J 0
(-2185 1650);
DISPLAY 0.617021 (-2185 1650);
PAINT SKYBLUE (-2185 1650);
FORCEPROP 1 LAST VALUE 0.0
J 0
(-2180 1800);
DISPLAY 0.617021 (-2180 1800);
PAINT SKYBLUE (-2180 1800);
FORCEPROP 1 LAST PACK_TYPE 0402
J 0
(-2185 1550);
DISPLAY 0.617021 (-2185 1550);
PAINT SKYBLUE (-2185 1550);
FORCEPROP 2 LAST ROOM PCIE_STEERING
J 0
(-2175 1900);
PAINT MONO (-2175 1900);
DISPLAY INVISIBLE (-2175 1900);
FORCEPROP 2 LAST CDS_LIB mstr_discrete
J 0
(-2225 1725);
PAINT MONO (-2225 1725);
DISPLAY INVISIBLE (-2225 1725);
FORCEPROP 1 LASTPIN (-2225 1625) $PN 2
J 0
(-2220 1635);
DISPLAY 0.787234 (-2220 1635);
PAINT ORANGE (-2220 1635);
DISPLAY INVISIBLE (-2220 1635);
FORCEPROP 1 LASTPIN (-2225 1825) $PN 1
J 0
(-2220 1787);
DISPLAY 0.787234 (-2220 1787);
PAINT ORANGE (-2220 1787);
DISPLAY INVISIBLE (-2220 1787);
FORCEPROP 0 LAST CDS_LOCATION R783
J 0
(-2175 1900);
PAINT MONO (-2175 1900);
DISPLAY INVISIBLE (-2175 1900);
FORCEPROP 0 LAST $SEC 1
J 0
(-2175 1900);
PAINT MONO (-2175 1900);
DISPLAY INVISIBLE (-2175 1900);
FORCEPROP 0 LAST CDS_SEC 1
J 0
(-2175 1900);
PAINT MONO (-2175 1900);
DISPLAY INVISIBLE (-2175 1900);
FORCEPROP 1 LAST PATH I77
J 0
(-2175 1900);
DISPLAY 0.978723 (-2175 1900);
PAINT WHITE (-2175 1900);
DISPLAY INVISIBLE (-2175 1900);
FORCEADD TAP..7
(-2025 1475);
FORCEPROP 3 LASTPIN (-2025 1525) SIG_NAME P3E_CPU0_PE1_PCH_CON_RXP<8>
J 0
(-2015 1535);
DISPLAY 0.659574 (-2015 1535);
PAINT MONO (-2015 1535);
DISPLAY INVISIBLE (-2015 1535);
FORCEPROP 1 LASTPIN (-2025 1525) BN 8
R 1
J 0
(-2032 1473);
DISPLAY 0.680851 (-2032 1473);
PAINT GREEN (-2032 1473);
FORCEPROP 1 LAST HDL_TAP TRUE
J 0
(-1705 1345);
DISPLAY 2.276596 (-1705 1345);
PAINT GREEN (-1705 1345);
DISPLAY INVISIBLE (-1705 1345);
FORCEPROP 1 LAST BODY_TYPE PLUMBING
J 0
(-1975 1475);
DISPLAY 2.276596 (-1975 1475);
PAINT GREEN (-1975 1475);
DISPLAY INVISIBLE (-1975 1475);
FORCEPROP 2 LAST CDS_LIB mstr_standard
J 0
(-2025 1475);
PAINT MONO (-2025 1475);
DISPLAY INVISIBLE (-2025 1475);
FORCEPROP 1 LAST PATH I78
J 0
(-2027 1475);
DISPLAY 0.872340 (-2027 1475);
PAINT GREEN (-2027 1475);
DISPLAY INVISIBLE (-2027 1475);
FORCEADD OFFPAGE..2
(-1725 1425);
FORCEPROP 2 LAST $XR1 109 
J 0
(-1536 1425);
DISPLAY 0.638298 (-1536 1425);
PAINT MONO (-1536 1425);
FORCEPROP 2 LAST $XR0 108 
J 0
(-1536 1425);
DISPLAY 0.638298 (-1536 1425);
PAINT MONO (-1536 1425);
FORCEPROP 2 LAST $XRERR ?
J 0
(-1536 1425);
DISPLAY 0.638298 (-1536 1425);
PAINT MONO (-1536 1425);
DISPLAY INVISIBLE (-1536 1425);
FORCEPROP 2 LAST $XRERR ?
J 0
(-1536 1425);
DISPLAY 0.638298 (-1536 1425);
PAINT MONO (-1536 1425);
DISPLAY INVISIBLE (-1536 1425);
FORCEPROP 2 LAST $XRERR ?
J 0
(-1536 1425);
DISPLAY 0.638298 (-1536 1425);
PAINT MONO (-1536 1425);
DISPLAY INVISIBLE (-1536 1425);
FORCEPROP 1 LAST COMMENT_BODY TRUE
J 0
(-1770 1330);
DISPLAY 0.872340 (-1770 1330);
PAINT GREEN (-1770 1330);
DISPLAY INVISIBLE (-1770 1330);
FORCEPROP 1 LAST OFFPAGE TRUE
J 0
(-1400 1300);
DISPLAY 0.872340 (-1400 1300);
PAINT GREEN (-1400 1300);
DISPLAY INVISIBLE (-1400 1300);
FORCEPROP 2 LAST CDS_LIB mstr_standard
J 0
(-1725 1425);
PAINT MONO (-1725 1425);
DISPLAY INVISIBLE (-1725 1425);
FORCEPROP 2 LAST PATH I79
J 0
(-1525 1475);
DISPLAY 1.021277 (-1525 1475);
PAINT ORANGE (-1525 1475);
DISPLAY INVISIBLE (-1525 1475);
FORCEADD CAP..1
R 2
(-5125 1725);
FORCEPROP 1 LAST TOLERANCE 10%
J 2
(-5175 1675);
DISPLAY 0.617021 (-5175 1675);
PAINT SKYBLUE (-5175 1675);
FORCEPROP 1 LAST PART_NUMBER A36096-155
J 2
(-5175 1575);
DISPLAY 0.617021 (-5175 1575);
PAINT BLUE (-5175 1575);
FORCEPROP 1 LAST PACK_TYPE 0402
J 2
(-5175 1525);
DISPLAY 0.617021 (-5175 1525);
PAINT SKYBLUE (-5175 1525);
FORCEPROP 1 LAST MATERIAL X7R
J 2
(-5175 1625);
DISPLAY 0.617021 (-5175 1625);
PAINT SKYBLUE (-5175 1625);
FORCEPROP 1 LAST VOLTAGE 16V
J 2
(-5175 1725);
DISPLAY 0.617021 (-5175 1725);
PAINT SKYBLUE (-5175 1725);
FORCEPROP 1 LAST VALUE 0.22UF
J 2
(-5175 1775);
DISPLAY 0.617021 (-5175 1775);
PAINT SKYBLUE (-5175 1775);
FORCEPROP 1 LAST $LOCATION C833
J 2
(-5175 1825);
DISPLAY 0.617021 (-5175 1825);
PAINT AQUA (-5175 1825);
FORCEPROP 2 LAST ROOM OCP_STEERING
J 2
(-5125 1725);
PAINT MONO (-5125 1725);
DISPLAY INVISIBLE (-5125 1725);
FORCEPROP 2 LAST CDS_LIB mstr_discrete
J 0
(-5125 1725);
PAINT MONO (-5125 1725);
DISPLAY INVISIBLE (-5125 1725);
FORCEPROP 1 LASTPIN (-5125 1625) $PN 2
J 2
(-5135 1605);
DISPLAY 0.787234 (-5135 1605);
PAINT ORANGE (-5135 1605);
DISPLAY INVISIBLE (-5135 1605);
FORCEPROP 1 LASTPIN (-5125 1825) $PN 1
J 2
(-5135 1805);
DISPLAY 0.787234 (-5135 1805);
PAINT ORANGE (-5135 1805);
DISPLAY INVISIBLE (-5135 1805);
FORCEPROP 2 LAST CDS_LOCATION C833
J 2
(-5175 1825);
DISPLAY 0.617021 (-5175 1825);
PAINT AQUA (-5175 1825);
DISPLAY INVISIBLE (-5175 1825);
FORCEPROP 0 LAST $SEC 1
J 0
(-5175 1875);
PAINT MONO (-5175 1875);
DISPLAY INVISIBLE (-5175 1875);
FORCEPROP 0 LAST CDS_SEC 1
J 0
(-5175 1875);
PAINT MONO (-5175 1875);
DISPLAY INVISIBLE (-5175 1875);
FORCEPROP 1 LAST PATH I8
J 2
(-5175 1875);
DISPLAY 0.978723 (-5175 1875);
PAINT WHITE (-5175 1875);
DISPLAY INVISIBLE (-5175 1875);
FORCEADD RES..2
(-2825 2025);
FORCEPROP 1 LAST $LOCATION R777
J 0
(-2780 2150);
DISPLAY 0.617021 (-2780 2150);
PAINT AQUA (-2780 2150);
FORCEPROP 1 LAST MATERIAL CHIP
J 0
(-2785 1950);
DISPLAY 0.617021 (-2785 1950);
PAINT SKYBLUE (-2785 1950);
FORCEPROP 1 LAST PART_NUMBER G21497-005
J 0
(-2785 1900);
DISPLAY 0.617021 (-2785 1900);
PAINT BLUE (-2785 1900);
FORCEPROP 1 LAST PACK_TYPE 0402
J 0
(-2785 1850);
DISPLAY 0.617021 (-2785 1850);
PAINT SKYBLUE (-2785 1850);
FORCEPROP 1 LAST VALUE 0.0
J 0
(-2780 2100);
DISPLAY 0.617021 (-2780 2100);
PAINT SKYBLUE (-2780 2100);
FORCEPROP 1 LAST TOLERANCE 5%
J 0
(-2780 2050);
DISPLAY 0.617021 (-2780 2050);
PAINT SKYBLUE (-2780 2050);
FORCEPROP 1 LAST WATTAGE 1/16W
J 0
(-2785 2000);
DISPLAY 0.617021 (-2785 2000);
PAINT SKYBLUE (-2785 2000);
FORCEPROP 2 LAST ROOM PCIE_STEERING
J 0
(-2775 2200);
PAINT MONO (-2775 2200);
DISPLAY INVISIBLE (-2775 2200);
FORCEPROP 2 LAST CDS_LIB mstr_discrete
J 0
(-2825 2025);
PAINT MONO (-2825 2025);
DISPLAY INVISIBLE (-2825 2025);
FORCEPROP 1 LASTPIN (-2825 1925) $PN 2
J 0
(-2820 1935);
DISPLAY 0.787234 (-2820 1935);
PAINT ORANGE (-2820 1935);
DISPLAY INVISIBLE (-2820 1935);
FORCEPROP 1 LASTPIN (-2825 2125) $PN 1
J 0
(-2820 2087);
DISPLAY 0.787234 (-2820 2087);
PAINT ORANGE (-2820 2087);
DISPLAY INVISIBLE (-2820 2087);
FORCEPROP 0 LAST CDS_LOCATION R777
J 0
(-2775 2200);
PAINT MONO (-2775 2200);
DISPLAY INVISIBLE (-2775 2200);
FORCEPROP 0 LAST $SEC 1
J 0
(-2775 2200);
PAINT MONO (-2775 2200);
DISPLAY INVISIBLE (-2775 2200);
FORCEPROP 0 LAST CDS_SEC 1
J 0
(-2775 2200);
PAINT MONO (-2775 2200);
DISPLAY INVISIBLE (-2775 2200);
FORCEPROP 1 LAST PATH I80
J 0
(-2775 2200);
DISPLAY 0.978723 (-2775 2200);
PAINT WHITE (-2775 2200);
DISPLAY INVISIBLE (-2775 2200);
FORCEADD TAP..3
(-3025 2275);
FORCEPROP 3 LASTPIN (-3025 2225) SIG_NAME P3E_CPU0_PE1_PCH_RXP<13>
J 0
(-3015 2235);
DISPLAY 0.659574 (-3015 2235);
PAINT MONO (-3015 2235);
DISPLAY INVISIBLE (-3015 2235);
FORCEPROP 1 LASTPIN (-3025 2225) BN 13
R 1
J 0
(-3032 2213);
DISPLAY 0.680851 (-3032 2213);
PAINT GREEN (-3032 2213);
FORCEPROP 1 LAST HDL_TAP TRUE
J 0
(-2705 2145);
DISPLAY 2.276596 (-2705 2145);
PAINT GREEN (-2705 2145);
DISPLAY INVISIBLE (-2705 2145);
FORCEPROP 1 LAST BODY_TYPE PLUMBING
J 0
(-2975 2225);
DISPLAY 2.276596 (-2975 2225);
PAINT GREEN (-2975 2225);
DISPLAY INVISIBLE (-2975 2225);
FORCEPROP 2 LAST CDS_LIB mstr_standard
J 0
(-3025 2275);
PAINT MONO (-3025 2275);
DISPLAY INVISIBLE (-3025 2275);
FORCEPROP 1 LAST PATH I81
J 0
(-3027 2275);
DISPLAY 0.872340 (-3027 2275);
PAINT GREEN (-3027 2275);
DISPLAY INVISIBLE (-3027 2275);
FORCEADD TAP..3
(-2825 2275);
FORCEPROP 3 LASTPIN (-2825 2225) SIG_NAME P3E_CPU0_PE1_PCH_RXP<12>
J 0
(-2815 2235);
DISPLAY 0.659574 (-2815 2235);
PAINT MONO (-2815 2235);
DISPLAY INVISIBLE (-2815 2235);
FORCEPROP 1 LASTPIN (-2825 2225) BN 12
R 1
J 0
(-2832 2213);
DISPLAY 0.680851 (-2832 2213);
PAINT GREEN (-2832 2213);
FORCEPROP 1 LAST HDL_TAP TRUE
J 0
(-2505 2145);
DISPLAY 2.276596 (-2505 2145);
PAINT GREEN (-2505 2145);
DISPLAY INVISIBLE (-2505 2145);
FORCEPROP 1 LAST BODY_TYPE PLUMBING
J 0
(-2775 2225);
DISPLAY 2.276596 (-2775 2225);
PAINT GREEN (-2775 2225);
DISPLAY INVISIBLE (-2775 2225);
FORCEPROP 2 LAST CDS_LIB mstr_standard
J 0
(-2825 2275);
PAINT MONO (-2825 2275);
DISPLAY INVISIBLE (-2825 2275);
FORCEPROP 1 LAST PATH I82
J 0
(-2827 2275);
DISPLAY 0.872340 (-2827 2275);
PAINT GREEN (-2827 2275);
DISPLAY INVISIBLE (-2827 2275);
FORCEADD TAP..3
(-2625 2275);
FORCEPROP 3 LASTPIN (-2625 2225) SIG_NAME P3E_CPU0_PE1_PCH_RXP<11>
J 0
(-2615 2235);
DISPLAY 0.659574 (-2615 2235);
PAINT MONO (-2615 2235);
DISPLAY INVISIBLE (-2615 2235);
FORCEPROP 1 LASTPIN (-2625 2225) BN 11
R 1
J 0
(-2632 2213);
DISPLAY 0.680851 (-2632 2213);
PAINT GREEN (-2632 2213);
FORCEPROP 1 LAST HDL_TAP TRUE
J 0
(-2305 2145);
DISPLAY 2.276596 (-2305 2145);
PAINT GREEN (-2305 2145);
DISPLAY INVISIBLE (-2305 2145);
FORCEPROP 1 LAST BODY_TYPE PLUMBING
J 0
(-2575 2225);
DISPLAY 2.276596 (-2575 2225);
PAINT GREEN (-2575 2225);
DISPLAY INVISIBLE (-2575 2225);
FORCEPROP 2 LAST CDS_LIB mstr_standard
J 0
(-2625 2275);
PAINT MONO (-2625 2275);
DISPLAY INVISIBLE (-2625 2275);
FORCEPROP 1 LAST PATH I83
J 0
(-2627 2275);
DISPLAY 0.872340 (-2627 2275);
PAINT GREEN (-2627 2275);
DISPLAY INVISIBLE (-2627 2275);
FORCEADD TAP..7
(-2900 2775);
FORCEPROP 3 LASTPIN (-2900 2825) SIG_NAME P3E_CPU0_PE1_PCH_CON_RXN<12>
J 0
(-2890 2835);
DISPLAY 0.659574 (-2890 2835);
PAINT MONO (-2890 2835);
DISPLAY INVISIBLE (-2890 2835);
FORCEPROP 1 LASTPIN (-2900 2825) BN 12
R 1
J 0
(-2907 2773);
DISPLAY 0.680851 (-2907 2773);
PAINT GREEN (-2907 2773);
FORCEPROP 1 LAST HDL_TAP TRUE
J 0
(-2580 2645);
DISPLAY 2.276596 (-2580 2645);
PAINT GREEN (-2580 2645);
DISPLAY INVISIBLE (-2580 2645);
FORCEPROP 1 LAST BODY_TYPE PLUMBING
J 0
(-2850 2775);
DISPLAY 2.276596 (-2850 2775);
PAINT GREEN (-2850 2775);
DISPLAY INVISIBLE (-2850 2775);
FORCEPROP 2 LAST CDS_LIB mstr_standard
J 0
(-2900 2775);
PAINT MONO (-2900 2775);
DISPLAY INVISIBLE (-2900 2775);
FORCEPROP 1 LAST PATH I84
J 0
(-2902 2775);
DISPLAY 0.872340 (-2902 2775);
PAINT GREEN (-2902 2775);
DISPLAY INVISIBLE (-2902 2775);
FORCEADD TAP..7
(-2700 2775);
FORCEPROP 3 LASTPIN (-2700 2825) SIG_NAME P3E_CPU0_PE1_PCH_CON_RXN<11>
J 0
(-2690 2835);
DISPLAY 0.659574 (-2690 2835);
PAINT MONO (-2690 2835);
DISPLAY INVISIBLE (-2690 2835);
FORCEPROP 1 LASTPIN (-2700 2825) BN 11
R 1
J 0
(-2707 2773);
DISPLAY 0.680851 (-2707 2773);
PAINT GREEN (-2707 2773);
FORCEPROP 1 LAST HDL_TAP TRUE
J 0
(-2380 2645);
DISPLAY 2.276596 (-2380 2645);
PAINT GREEN (-2380 2645);
DISPLAY INVISIBLE (-2380 2645);
FORCEPROP 1 LAST BODY_TYPE PLUMBING
J 0
(-2650 2775);
DISPLAY 2.276596 (-2650 2775);
PAINT GREEN (-2650 2775);
DISPLAY INVISIBLE (-2650 2775);
FORCEPROP 2 LAST CDS_LIB mstr_standard
J 0
(-2700 2775);
PAINT MONO (-2700 2775);
DISPLAY INVISIBLE (-2700 2775);
FORCEPROP 1 LAST PATH I85
J 0
(-2702 2775);
DISPLAY 0.872340 (-2702 2775);
PAINT GREEN (-2702 2775);
DISPLAY INVISIBLE (-2702 2775);
FORCEADD RES..2
(-2425 2025);
FORCEPROP 1 LAST $LOCATION R781
J 0
(-2380 2150);
DISPLAY 0.617021 (-2380 2150);
PAINT AQUA (-2380 2150);
FORCEPROP 1 LAST VALUE 0.0
J 0
(-2380 2100);
DISPLAY 0.617021 (-2380 2100);
PAINT SKYBLUE (-2380 2100);
FORCEPROP 1 LAST TOLERANCE 5%
J 0
(-2380 2050);
DISPLAY 0.617021 (-2380 2050);
PAINT SKYBLUE (-2380 2050);
FORCEPROP 1 LAST WATTAGE 1/16W
J 0
(-2385 2000);
DISPLAY 0.617021 (-2385 2000);
PAINT SKYBLUE (-2385 2000);
FORCEPROP 1 LAST PACK_TYPE 0402
J 0
(-2385 1850);
DISPLAY 0.617021 (-2385 1850);
PAINT SKYBLUE (-2385 1850);
FORCEPROP 1 LAST PART_NUMBER G21497-005
J 0
(-2385 1900);
DISPLAY 0.617021 (-2385 1900);
PAINT BLUE (-2385 1900);
FORCEPROP 1 LAST MATERIAL CHIP
J 0
(-2385 1950);
DISPLAY 0.617021 (-2385 1950);
PAINT SKYBLUE (-2385 1950);
FORCEPROP 2 LAST ROOM PCIE_STEERING
J 0
(-2375 2200);
PAINT MONO (-2375 2200);
DISPLAY INVISIBLE (-2375 2200);
FORCEPROP 2 LAST CDS_LIB mstr_discrete
J 0
(-2425 2025);
PAINT MONO (-2425 2025);
DISPLAY INVISIBLE (-2425 2025);
FORCEPROP 1 LASTPIN (-2425 1925) $PN 2
J 0
(-2420 1935);
DISPLAY 0.787234 (-2420 1935);
PAINT ORANGE (-2420 1935);
DISPLAY INVISIBLE (-2420 1935);
FORCEPROP 1 LASTPIN (-2425 2125) $PN 1
J 0
(-2420 2087);
DISPLAY 0.787234 (-2420 2087);
PAINT ORANGE (-2420 2087);
DISPLAY INVISIBLE (-2420 2087);
FORCEPROP 0 LAST CDS_LOCATION R781
J 0
(-2375 2200);
PAINT MONO (-2375 2200);
DISPLAY INVISIBLE (-2375 2200);
FORCEPROP 0 LAST $SEC 1
J 0
(-2375 2200);
PAINT MONO (-2375 2200);
DISPLAY INVISIBLE (-2375 2200);
FORCEPROP 0 LAST CDS_SEC 1
J 0
(-2375 2200);
PAINT MONO (-2375 2200);
DISPLAY INVISIBLE (-2375 2200);
FORCEPROP 1 LAST PATH I86
J 0
(-2375 2200);
DISPLAY 0.978723 (-2375 2200);
PAINT WHITE (-2375 2200);
DISPLAY INVISIBLE (-2375 2200);
FORCEADD TAP..3
(-2425 2275);
FORCEPROP 3 LASTPIN (-2425 2225) SIG_NAME P3E_CPU0_PE1_PCH_RXP<10>
J 0
(-2415 2235);
DISPLAY 0.659574 (-2415 2235);
PAINT MONO (-2415 2235);
DISPLAY INVISIBLE (-2415 2235);
FORCEPROP 1 LASTPIN (-2425 2225) BN 10
R 1
J 0
(-2432 2213);
DISPLAY 0.680851 (-2432 2213);
PAINT GREEN (-2432 2213);
FORCEPROP 1 LAST HDL_TAP TRUE
J 0
(-2105 2145);
DISPLAY 2.276596 (-2105 2145);
PAINT GREEN (-2105 2145);
DISPLAY INVISIBLE (-2105 2145);
FORCEPROP 1 LAST BODY_TYPE PLUMBING
J 0
(-2375 2225);
DISPLAY 2.276596 (-2375 2225);
PAINT GREEN (-2375 2225);
DISPLAY INVISIBLE (-2375 2225);
FORCEPROP 2 LAST CDS_LIB mstr_standard
J 0
(-2425 2275);
PAINT MONO (-2425 2275);
DISPLAY INVISIBLE (-2425 2275);
FORCEPROP 1 LAST PATH I87
J 0
(-2427 2275);
DISPLAY 0.872340 (-2427 2275);
PAINT GREEN (-2427 2275);
DISPLAY INVISIBLE (-2427 2275);
FORCEADD TAP..3
(-2225 2275);
FORCEPROP 3 LASTPIN (-2225 2225) SIG_NAME P3E_CPU0_PE1_PCH_RXP<9>
J 0
(-2215 2235);
DISPLAY 0.659574 (-2215 2235);
PAINT MONO (-2215 2235);
DISPLAY INVISIBLE (-2215 2235);
FORCEPROP 1 LASTPIN (-2225 2225) BN 9
R 1
J 0
(-2232 2213);
DISPLAY 0.680851 (-2232 2213);
PAINT GREEN (-2232 2213);
FORCEPROP 1 LAST HDL_TAP TRUE
J 0
(-1905 2145);
DISPLAY 2.276596 (-1905 2145);
PAINT GREEN (-1905 2145);
DISPLAY INVISIBLE (-1905 2145);
FORCEPROP 1 LAST BODY_TYPE PLUMBING
J 0
(-2175 2225);
DISPLAY 2.276596 (-2175 2225);
PAINT GREEN (-2175 2225);
DISPLAY INVISIBLE (-2175 2225);
FORCEPROP 2 LAST CDS_LIB mstr_standard
J 0
(-2225 2275);
PAINT MONO (-2225 2275);
DISPLAY INVISIBLE (-2225 2275);
FORCEPROP 1 LAST PATH I88
J 0
(-2227 2275);
DISPLAY 0.872340 (-2227 2275);
PAINT GREEN (-2227 2275);
DISPLAY INVISIBLE (-2227 2275);
FORCEADD TAP..3
(-2025 2275);
FORCEPROP 3 LASTPIN (-2025 2225) SIG_NAME P3E_CPU0_PE1_PCH_RXP<8>
J 0
(-2015 2235);
DISPLAY 0.659574 (-2015 2235);
PAINT MONO (-2015 2235);
DISPLAY INVISIBLE (-2015 2235);
FORCEPROP 1 LASTPIN (-2025 2225) BN 8
R 1
J 0
(-2032 2213);
DISPLAY 0.680851 (-2032 2213);
PAINT GREEN (-2032 2213);
FORCEPROP 1 LAST HDL_TAP TRUE
J 0
(-1705 2145);
DISPLAY 2.276596 (-1705 2145);
PAINT GREEN (-1705 2145);
DISPLAY INVISIBLE (-1705 2145);
FORCEPROP 1 LAST BODY_TYPE PLUMBING
J 0
(-1975 2225);
DISPLAY 2.276596 (-1975 2225);
PAINT GREEN (-1975 2225);
DISPLAY INVISIBLE (-1975 2225);
FORCEPROP 2 LAST CDS_LIB mstr_standard
J 0
(-2025 2275);
PAINT MONO (-2025 2275);
DISPLAY INVISIBLE (-2025 2275);
FORCEPROP 1 LAST PATH I89
J 0
(-2027 2275);
DISPLAY 0.872340 (-2027 2275);
PAINT GREEN (-2027 2275);
DISPLAY INVISIBLE (-2027 2275);
FORCEADD OFFPAGE..1
(-6100 2325);
FORCEPROP 2 LAST $XR0 30 
J 0
(-6321 2325);
DISPLAY 0.638298 (-6321 2325);
PAINT MONO (-6321 2325);
FORCEPROP 2 LAST $XR1 105 
J 0
(-6441 2325);
DISPLAY 0.638298 (-6441 2325);
PAINT MONO (-6441 2325);
FORCEPROP 1 LAST COMMENT_BODY TRUE
J 0
(-5980 2225);
DISPLAY 2.276596 (-5980 2225);
PAINT GREEN (-5980 2225);
DISPLAY INVISIBLE (-5980 2225);
FORCEPROP 1 LAST OFFPAGE TRUE
J 0
(-5780 2195);
PAINT GREEN (-5780 2195);
DISPLAY INVISIBLE (-5780 2195);
FORCEPROP 2 LAST CDS_LIB mstr_standard
J 0
(-6100 2325);
PAINT MONO (-6100 2325);
DISPLAY INVISIBLE (-6100 2325);
FORCEPROP 2 LAST PATH I9
J 0
(-6300 2375);
DISPLAY 1.021277 (-6300 2375);
PAINT ORANGE (-6300 2375);
DISPLAY INVISIBLE (-6300 2375);
FORCEADD TAP..7
(-2500 2775);
FORCEPROP 3 LASTPIN (-2500 2825) SIG_NAME P3E_CPU0_PE1_PCH_CON_RXN<10>
J 0
(-2490 2835);
DISPLAY 0.659574 (-2490 2835);
PAINT MONO (-2490 2835);
DISPLAY INVISIBLE (-2490 2835);
FORCEPROP 1 LASTPIN (-2500 2825) BN 10
R 1
J 0
(-2507 2773);
DISPLAY 0.680851 (-2507 2773);
PAINT GREEN (-2507 2773);
FORCEPROP 1 LAST HDL_TAP TRUE
J 0
(-2180 2645);
DISPLAY 2.276596 (-2180 2645);
PAINT GREEN (-2180 2645);
DISPLAY INVISIBLE (-2180 2645);
FORCEPROP 1 LAST BODY_TYPE PLUMBING
J 0
(-2450 2775);
DISPLAY 2.276596 (-2450 2775);
PAINT GREEN (-2450 2775);
DISPLAY INVISIBLE (-2450 2775);
FORCEPROP 2 LAST CDS_LIB mstr_standard
J 0
(-2500 2775);
PAINT MONO (-2500 2775);
DISPLAY INVISIBLE (-2500 2775);
FORCEPROP 1 LAST PATH I90
J 0
(-2502 2775);
DISPLAY 0.872340 (-2502 2775);
PAINT GREEN (-2502 2775);
DISPLAY INVISIBLE (-2502 2775);
FORCEADD TAP..7
(-2300 2775);
FORCEPROP 3 LASTPIN (-2300 2825) SIG_NAME P3E_CPU0_PE1_PCH_CON_RXN<9>
J 0
(-2290 2835);
DISPLAY 0.659574 (-2290 2835);
PAINT MONO (-2290 2835);
DISPLAY INVISIBLE (-2290 2835);
FORCEPROP 1 LASTPIN (-2300 2825) BN 9
R 1
J 0
(-2307 2773);
DISPLAY 0.680851 (-2307 2773);
PAINT GREEN (-2307 2773);
FORCEPROP 1 LAST HDL_TAP TRUE
J 0
(-1980 2645);
DISPLAY 2.276596 (-1980 2645);
PAINT GREEN (-1980 2645);
DISPLAY INVISIBLE (-1980 2645);
FORCEPROP 1 LAST BODY_TYPE PLUMBING
J 0
(-2250 2775);
DISPLAY 2.276596 (-2250 2775);
PAINT GREEN (-2250 2775);
DISPLAY INVISIBLE (-2250 2775);
FORCEPROP 2 LAST CDS_LIB mstr_standard
J 0
(-2300 2775);
PAINT MONO (-2300 2775);
DISPLAY INVISIBLE (-2300 2775);
FORCEPROP 1 LAST PATH I91
J 0
(-2302 2775);
DISPLAY 0.872340 (-2302 2775);
PAINT GREEN (-2302 2775);
DISPLAY INVISIBLE (-2302 2775);
FORCEADD TAP..7
(-2100 2775);
FORCEPROP 3 LASTPIN (-2100 2825) SIG_NAME P3E_CPU0_PE1_PCH_CON_RXN<8>
J 0
(-2090 2835);
DISPLAY 0.659574 (-2090 2835);
PAINT MONO (-2090 2835);
DISPLAY INVISIBLE (-2090 2835);
FORCEPROP 1 LASTPIN (-2100 2825) BN 8
R 1
J 0
(-2107 2773);
DISPLAY 0.680851 (-2107 2773);
PAINT GREEN (-2107 2773);
FORCEPROP 1 LAST HDL_TAP TRUE
J 0
(-1780 2645);
DISPLAY 2.276596 (-1780 2645);
PAINT GREEN (-1780 2645);
DISPLAY INVISIBLE (-1780 2645);
FORCEPROP 1 LAST BODY_TYPE PLUMBING
J 0
(-2050 2775);
DISPLAY 2.276596 (-2050 2775);
PAINT GREEN (-2050 2775);
DISPLAY INVISIBLE (-2050 2775);
FORCEPROP 2 LAST CDS_LIB mstr_standard
J 0
(-2100 2775);
PAINT MONO (-2100 2775);
DISPLAY INVISIBLE (-2100 2775);
FORCEPROP 1 LAST PATH I92
J 0
(-2102 2775);
DISPLAY 0.872340 (-2102 2775);
PAINT GREEN (-2102 2775);
DISPLAY INVISIBLE (-2102 2775);
FORCEADD RES..2
(-2900 3325);
FORCEPROP 1 LAST MATERIAL CHIP
J 0
(-2860 3250);
DISPLAY 0.617021 (-2860 3250);
PAINT SKYBLUE (-2860 3250);
FORCEPROP 1 LAST PART_NUMBER G21497-005
J 0
(-2860 3200);
DISPLAY 0.617021 (-2860 3200);
PAINT BLUE (-2860 3200);
FORCEPROP 1 LAST PACK_TYPE 0402
J 0
(-2860 3150);
DISPLAY 0.617021 (-2860 3150);
PAINT SKYBLUE (-2860 3150);
FORCEPROP 1 LAST VALUE 0.0
J 0
(-2855 3400);
DISPLAY 0.617021 (-2855 3400);
PAINT SKYBLUE (-2855 3400);
FORCEPROP 1 LAST TOLERANCE 5%
J 0
(-2855 3350);
DISPLAY 0.617021 (-2855 3350);
PAINT SKYBLUE (-2855 3350);
FORCEPROP 1 LAST WATTAGE 1/16W
J 0
(-2860 3300);
DISPLAY 0.617021 (-2860 3300);
PAINT SKYBLUE (-2860 3300);
FORCEPROP 1 LAST $LOCATION R775
J 0
(-2855 3450);
DISPLAY 0.617021 (-2855 3450);
PAINT AQUA (-2855 3450);
FORCEPROP 2 LAST ROOM PCIE_STEERING
J 0
(-2850 3500);
PAINT MONO (-2850 3500);
DISPLAY INVISIBLE (-2850 3500);
FORCEPROP 2 LAST CDS_LIB mstr_discrete
J 0
(-2900 3325);
PAINT MONO (-2900 3325);
DISPLAY INVISIBLE (-2900 3325);
FORCEPROP 1 LASTPIN (-2900 3225) $PN 2
J 0
(-2895 3235);
DISPLAY 0.787234 (-2895 3235);
PAINT ORANGE (-2895 3235);
DISPLAY INVISIBLE (-2895 3235);
FORCEPROP 1 LASTPIN (-2900 3425) $PN 1
J 0
(-2895 3387);
DISPLAY 0.787234 (-2895 3387);
PAINT ORANGE (-2895 3387);
DISPLAY INVISIBLE (-2895 3387);
FORCEPROP 0 LAST CDS_LOCATION R775
J 0
(-2850 3500);
PAINT MONO (-2850 3500);
DISPLAY INVISIBLE (-2850 3500);
FORCEPROP 0 LAST $SEC 1
J 0
(-2850 3500);
PAINT MONO (-2850 3500);
DISPLAY INVISIBLE (-2850 3500);
FORCEPROP 0 LAST CDS_SEC 1
J 0
(-2850 3500);
PAINT MONO (-2850 3500);
DISPLAY INVISIBLE (-2850 3500);
FORCEPROP 1 LAST PATH I93
J 0
(-2850 3500);
DISPLAY 0.978723 (-2850 3500);
PAINT WHITE (-2850 3500);
DISPLAY INVISIBLE (-2850 3500);
FORCEADD RES..2
(-2700 3025);
FORCEPROP 1 LAST PACK_TYPE 0402
J 0
(-2660 2850);
DISPLAY 0.617021 (-2660 2850);
PAINT SKYBLUE (-2660 2850);
FORCEPROP 1 LAST PART_NUMBER G21497-005
J 0
(-2660 2900);
DISPLAY 0.617021 (-2660 2900);
PAINT BLUE (-2660 2900);
FORCEPROP 1 LAST TOLERANCE 5%
J 0
(-2655 3050);
DISPLAY 0.617021 (-2655 3050);
PAINT SKYBLUE (-2655 3050);
FORCEPROP 1 LAST WATTAGE 1/16W
J 0
(-2660 3000);
DISPLAY 0.617021 (-2660 3000);
PAINT SKYBLUE (-2660 3000);
FORCEPROP 1 LAST MATERIAL CHIP
J 0
(-2660 2950);
DISPLAY 0.617021 (-2660 2950);
PAINT SKYBLUE (-2660 2950);
FORCEPROP 1 LAST VALUE 0.0
J 0
(-2655 3100);
DISPLAY 0.617021 (-2655 3100);
PAINT SKYBLUE (-2655 3100);
FORCEPROP 1 LAST $LOCATION R778
J 0
(-2655 3150);
DISPLAY 0.617021 (-2655 3150);
PAINT AQUA (-2655 3150);
FORCEPROP 2 LAST ROOM PCIE_STEERING
J 0
(-2650 3200);
PAINT MONO (-2650 3200);
DISPLAY INVISIBLE (-2650 3200);
FORCEPROP 2 LAST CDS_LIB mstr_discrete
J 0
(-2700 3025);
PAINT MONO (-2700 3025);
DISPLAY INVISIBLE (-2700 3025);
FORCEPROP 1 LASTPIN (-2700 2925) $PN 2
J 0
(-2695 2935);
DISPLAY 0.787234 (-2695 2935);
PAINT ORANGE (-2695 2935);
DISPLAY INVISIBLE (-2695 2935);
FORCEPROP 1 LASTPIN (-2700 3125) $PN 1
J 0
(-2695 3087);
DISPLAY 0.787234 (-2695 3087);
PAINT ORANGE (-2695 3087);
DISPLAY INVISIBLE (-2695 3087);
FORCEPROP 0 LAST CDS_LOCATION R778
J 0
(-2650 3200);
PAINT MONO (-2650 3200);
DISPLAY INVISIBLE (-2650 3200);
FORCEPROP 0 LAST $SEC 1
J 0
(-2650 3200);
PAINT MONO (-2650 3200);
DISPLAY INVISIBLE (-2650 3200);
FORCEPROP 0 LAST CDS_SEC 1
J 0
(-2650 3200);
PAINT MONO (-2650 3200);
DISPLAY INVISIBLE (-2650 3200);
FORCEPROP 1 LAST PATH I94
J 0
(-2650 3200);
DISPLAY 0.978723 (-2650 3200);
PAINT WHITE (-2650 3200);
DISPLAY INVISIBLE (-2650 3200);
FORCEADD TAP..3
(-2900 3575);
FORCEPROP 3 LASTPIN (-2900 3525) SIG_NAME P3E_CPU0_PE1_PCH_RXN<12>
J 0
(-2890 3535);
DISPLAY 0.659574 (-2890 3535);
PAINT MONO (-2890 3535);
DISPLAY INVISIBLE (-2890 3535);
FORCEPROP 1 LASTPIN (-2900 3525) BN 12
R 1
J 0
(-2907 3513);
DISPLAY 0.680851 (-2907 3513);
PAINT GREEN (-2907 3513);
FORCEPROP 1 LAST HDL_TAP TRUE
J 0
(-2580 3445);
DISPLAY 2.276596 (-2580 3445);
PAINT GREEN (-2580 3445);
DISPLAY INVISIBLE (-2580 3445);
FORCEPROP 1 LAST BODY_TYPE PLUMBING
J 0
(-2850 3525);
DISPLAY 2.276596 (-2850 3525);
PAINT GREEN (-2850 3525);
DISPLAY INVISIBLE (-2850 3525);
FORCEPROP 2 LAST CDS_LIB mstr_standard
J 0
(-2900 3575);
PAINT MONO (-2900 3575);
DISPLAY INVISIBLE (-2900 3575);
FORCEPROP 1 LAST PATH I95
J 0
(-2902 3575);
DISPLAY 0.872340 (-2902 3575);
PAINT GREEN (-2902 3575);
DISPLAY INVISIBLE (-2902 3575);
FORCEADD TAP..3
(-2700 3575);
FORCEPROP 3 LASTPIN (-2700 3525) SIG_NAME P3E_CPU0_PE1_PCH_RXN<11>
J 0
(-2690 3535);
DISPLAY 0.659574 (-2690 3535);
PAINT MONO (-2690 3535);
DISPLAY INVISIBLE (-2690 3535);
FORCEPROP 1 LASTPIN (-2700 3525) BN 11
R 1
J 0
(-2707 3513);
DISPLAY 0.680851 (-2707 3513);
PAINT GREEN (-2707 3513);
FORCEPROP 1 LAST HDL_TAP TRUE
J 0
(-2380 3445);
DISPLAY 2.276596 (-2380 3445);
PAINT GREEN (-2380 3445);
DISPLAY INVISIBLE (-2380 3445);
FORCEPROP 1 LAST BODY_TYPE PLUMBING
J 0
(-2650 3525);
DISPLAY 2.276596 (-2650 3525);
PAINT GREEN (-2650 3525);
DISPLAY INVISIBLE (-2650 3525);
FORCEPROP 2 LAST CDS_LIB mstr_standard
J 0
(-2700 3575);
PAINT MONO (-2700 3575);
DISPLAY INVISIBLE (-2700 3575);
FORCEPROP 1 LAST PATH I96
J 0
(-2702 3575);
DISPLAY 0.872340 (-2702 3575);
PAINT GREEN (-2702 3575);
DISPLAY INVISIBLE (-2702 3575);
FORCEADD RES..2
(-2500 3325);
FORCEPROP 1 LAST PART_NUMBER G21497-005
J 0
(-2460 3200);
DISPLAY 0.617021 (-2460 3200);
PAINT BLUE (-2460 3200);
FORCEPROP 1 LAST VALUE 0.0
J 0
(-2455 3400);
DISPLAY 0.617021 (-2455 3400);
PAINT SKYBLUE (-2455 3400);
FORCEPROP 1 LAST TOLERANCE 5%
J 0
(-2455 3350);
DISPLAY 0.617021 (-2455 3350);
PAINT SKYBLUE (-2455 3350);
FORCEPROP 1 LAST WATTAGE 1/16W
J 0
(-2460 3300);
DISPLAY 0.617021 (-2460 3300);
PAINT SKYBLUE (-2460 3300);
FORCEPROP 1 LAST MATERIAL CHIP
J 0
(-2460 3250);
DISPLAY 0.617021 (-2460 3250);
PAINT SKYBLUE (-2460 3250);
FORCEPROP 1 LAST PACK_TYPE 0402
J 0
(-2460 3150);
DISPLAY 0.617021 (-2460 3150);
PAINT SKYBLUE (-2460 3150);
FORCEPROP 1 LAST $LOCATION R780
J 0
(-2455 3450);
DISPLAY 0.617021 (-2455 3450);
PAINT AQUA (-2455 3450);
FORCEPROP 2 LAST ROOM PCIE_STEERING
J 0
(-2450 3500);
PAINT MONO (-2450 3500);
DISPLAY INVISIBLE (-2450 3500);
FORCEPROP 2 LAST CDS_LIB mstr_discrete
J 0
(-2500 3325);
PAINT MONO (-2500 3325);
DISPLAY INVISIBLE (-2500 3325);
FORCEPROP 1 LASTPIN (-2500 3225) $PN 2
J 0
(-2495 3235);
DISPLAY 0.787234 (-2495 3235);
PAINT ORANGE (-2495 3235);
DISPLAY INVISIBLE (-2495 3235);
FORCEPROP 1 LASTPIN (-2500 3425) $PN 1
J 0
(-2495 3387);
DISPLAY 0.787234 (-2495 3387);
PAINT ORANGE (-2495 3387);
DISPLAY INVISIBLE (-2495 3387);
FORCEPROP 0 LAST CDS_LOCATION R780
J 0
(-2450 3500);
PAINT MONO (-2450 3500);
DISPLAY INVISIBLE (-2450 3500);
FORCEPROP 0 LAST $SEC 1
J 0
(-2450 3500);
PAINT MONO (-2450 3500);
DISPLAY INVISIBLE (-2450 3500);
FORCEPROP 0 LAST CDS_SEC 1
J 0
(-2450 3500);
PAINT MONO (-2450 3500);
DISPLAY INVISIBLE (-2450 3500);
FORCEPROP 1 LAST PATH I97
J 0
(-2450 3500);
DISPLAY 0.978723 (-2450 3500);
PAINT WHITE (-2450 3500);
DISPLAY INVISIBLE (-2450 3500);
FORCEADD RES..2
(-2300 3025);
FORCEPROP 1 LAST VALUE 0.0
J 0
(-2255 3100);
DISPLAY 0.617021 (-2255 3100);
PAINT SKYBLUE (-2255 3100);
FORCEPROP 1 LAST $LOCATION R782
J 0
(-2255 3150);
DISPLAY 0.617021 (-2255 3150);
PAINT AQUA (-2255 3150);
FORCEPROP 1 LAST PART_NUMBER G21497-005
J 0
(-2260 2900);
DISPLAY 0.617021 (-2260 2900);
PAINT BLUE (-2260 2900);
FORCEPROP 1 LAST MATERIAL CHIP
J 0
(-2260 2950);
DISPLAY 0.617021 (-2260 2950);
PAINT SKYBLUE (-2260 2950);
FORCEPROP 1 LAST WATTAGE 1/16W
J 0
(-2260 3000);
DISPLAY 0.617021 (-2260 3000);
PAINT SKYBLUE (-2260 3000);
FORCEPROP 1 LAST TOLERANCE 5%
J 0
(-2255 3050);
DISPLAY 0.617021 (-2255 3050);
PAINT SKYBLUE (-2255 3050);
FORCEPROP 1 LAST PACK_TYPE 0402
J 0
(-2260 2850);
DISPLAY 0.617021 (-2260 2850);
PAINT SKYBLUE (-2260 2850);
FORCEPROP 2 LAST ROOM PCIE_STEERING
J 0
(-2250 3200);
PAINT MONO (-2250 3200);
DISPLAY INVISIBLE (-2250 3200);
FORCEPROP 2 LAST CDS_LIB mstr_discrete
J 0
(-2300 3025);
PAINT MONO (-2300 3025);
DISPLAY INVISIBLE (-2300 3025);
FORCEPROP 1 LASTPIN (-2300 2925) $PN 2
J 0
(-2295 2935);
DISPLAY 0.787234 (-2295 2935);
PAINT ORANGE (-2295 2935);
DISPLAY INVISIBLE (-2295 2935);
FORCEPROP 1 LASTPIN (-2300 3125) $PN 1
J 0
(-2295 3087);
DISPLAY 0.787234 (-2295 3087);
PAINT ORANGE (-2295 3087);
DISPLAY INVISIBLE (-2295 3087);
FORCEPROP 0 LAST CDS_LOCATION R782
J 0
(-2250 3200);
PAINT MONO (-2250 3200);
DISPLAY INVISIBLE (-2250 3200);
FORCEPROP 0 LAST $SEC 1
J 0
(-2250 3200);
PAINT MONO (-2250 3200);
DISPLAY INVISIBLE (-2250 3200);
FORCEPROP 0 LAST CDS_SEC 1
J 0
(-2250 3200);
PAINT MONO (-2250 3200);
DISPLAY INVISIBLE (-2250 3200);
FORCEPROP 1 LAST PATH I98
J 0
(-2250 3200);
DISPLAY 0.978723 (-2250 3200);
PAINT WHITE (-2250 3200);
DISPLAY INVISIBLE (-2250 3200);
FORCEADD RES..2
(-2100 3325);
FORCEPROP 1 LAST PART_NUMBER G21497-005
J 0
(-2060 3200);
DISPLAY 0.617021 (-2060 3200);
PAINT BLUE (-2060 3200);
FORCEPROP 1 LAST PACK_TYPE 0402
J 0
(-2060 3150);
DISPLAY 0.617021 (-2060 3150);
PAINT SKYBLUE (-2060 3150);
FORCEPROP 1 LAST MATERIAL CHIP
J 0
(-2060 3250);
DISPLAY 0.617021 (-2060 3250);
PAINT SKYBLUE (-2060 3250);
FORCEPROP 1 LAST TOLERANCE 5%
J 0
(-2055 3350);
DISPLAY 0.617021 (-2055 3350);
PAINT SKYBLUE (-2055 3350);
FORCEPROP 1 LAST VALUE 0.0
J 0
(-2055 3400);
DISPLAY 0.617021 (-2055 3400);
PAINT SKYBLUE (-2055 3400);
FORCEPROP 1 LAST WATTAGE 1/16W
J 0
(-2060 3300);
DISPLAY 0.617021 (-2060 3300);
PAINT SKYBLUE (-2060 3300);
FORCEPROP 1 LAST $LOCATION R784
J 0
(-2055 3450);
DISPLAY 0.617021 (-2055 3450);
PAINT AQUA (-2055 3450);
FORCEPROP 2 LAST ROOM PCIE_STEERING
J 0
(-2050 3500);
PAINT MONO (-2050 3500);
DISPLAY INVISIBLE (-2050 3500);
FORCEPROP 2 LAST CDS_LIB mstr_discrete
J 0
(-2100 3325);
PAINT MONO (-2100 3325);
DISPLAY INVISIBLE (-2100 3325);
FORCEPROP 1 LASTPIN (-2100 3225) $PN 2
J 0
(-2095 3235);
DISPLAY 0.787234 (-2095 3235);
PAINT ORANGE (-2095 3235);
DISPLAY INVISIBLE (-2095 3235);
FORCEPROP 1 LASTPIN (-2100 3425) $PN 1
J 0
(-2095 3387);
DISPLAY 0.787234 (-2095 3387);
PAINT ORANGE (-2095 3387);
DISPLAY INVISIBLE (-2095 3387);
FORCEPROP 0 LAST CDS_LOCATION R784
J 0
(-2050 3500);
PAINT MONO (-2050 3500);
DISPLAY INVISIBLE (-2050 3500);
FORCEPROP 0 LAST $SEC 1
J 0
(-2050 3500);
PAINT MONO (-2050 3500);
DISPLAY INVISIBLE (-2050 3500);
FORCEPROP 0 LAST CDS_SEC 1
J 0
(-2050 3500);
PAINT MONO (-2050 3500);
DISPLAY INVISIBLE (-2050 3500);
FORCEPROP 1 LAST PATH I99
J 0
(-2050 3500);
DISPLAY 0.978723 (-2050 3500);
PAINT WHITE (-2050 3500);
DISPLAY INVISIBLE (-2050 3500);
FORCEADD INTEL_CORP_BPAGE..1
(0 0);
FORCEPROP 1 LAST CDS_CON_LAST_MODIFIED Tue Dec 01 11:52:32 2015
J 0
(-1425 325);
PAINT ORANGE (-1425 325);
DISPLAY INVISIBLE (-1425 325);
FORCEPROP 1 LAST CUSTOM_TXT_CDS <CURRENT_DESIGN_SHEET> OF <TOTAL_DESIGN_SHEETS>
J 0
(-500 25);
PAINT GREEN (-500 25);
FORCEPROP 1 LAST CUSTOM_TXT_CDS <CON_LAST_MODIFIED>
J 0
(-1925 350);
PAINT GREEN (-1925 350);
FORCEPROP 2 LAST CUSTOM_TXT_CDS <XR_PAGE_TITLE>
J 0
(-7890 5250);
DISPLAY 0.638298 (-7890 5250);
PAINT PINK (-7890 5250);
DISPLAY INVISIBLE (-7890 5250);
FORCEPROP 1 LAST SCH_ADDRESS1 2200 Mission College Blvd.
J 0
(-3975 125);
DISPLAY 0.872340 (-3975 125);
PAINT GREEN (-3975 125);
FORCEPROP 1 LAST SCH_ADDRESS2 P.O. BOX 58119
J 0
(-3975 75);
DISPLAY 0.872340 (-3975 75);
PAINT GREEN (-3975 75);
FORCEPROP 1 LAST SCH_ADDRESS3 Santa Clara, CA 95052-8119
J 0
(-3975 25);
DISPLAY 0.872340 (-3975 25);
PAINT GREEN (-3975 25);
FORCEPROP 1 LAST SCH_DEPT UNKNOWN
J 1
(-4450 100);
DISPLAY 1.255319 (-4450 100);
PAINT ORANGE (-4450 100);
FORCEPROP 1 LAST SCH_REV 0.1
J 0
(-250 150);
DISPLAY 1.170213 (-250 150);
PAINT GREEN (-250 150);
FORCEPROP 1 LAST SCH_NUMBER 000000-000
J 0
(-1300 150);
DISPLAY 1.702128 (-1300 150);
PAINT GREEN (-1300 150);
FORCEPROP 1 LAST SCH_TITLE x8 PCIe Co-lay path
J 0
(-7950 50);
DISPLAY 2.468085 (-7950 50);
PAINT ORANGE (-7950 50);
FORCEPROP 1 LAST COMMENT_BODY TRUE
J 0
(12 12);
DISPLAY 0.468085 (12 12);
PAINT GREEN (12 12);
DISPLAY INVISIBLE (12 12);
FORCEPROP 2 LAST CDS_LIB mstr_symbols
J 0
(0 0);
PAINT MONO (0 0);
DISPLAY INVISIBLE (0 0);
FORCEPROP 2 LAST PAGE_BORDER TRUE
J 0
(-7890 5250);
DISPLAY 0.638298 (-7890 5250);
PAINT PINK (-7890 5250);
DISPLAY INVISIBLE (-7890 5250);
FORCEPROP 2 LAST CDS_XR_PAGE_TITLE CR-244 : @BASEBOARD_FAB2_LIB.BASEBOARD_FAB2(SCH_1):PAGE244
J 0
(-7890 5250);
DISPLAY 0.638298 (-7890 5250);
PAINT PINK (-7890 5250);
DISPLAY INVISIBLE (-7890 5250);
WIRE 17 -1 (-5700 1425)(-5900 1425);
WIRE 17 -1 (-5500 1425)(-5700 1425);
FORCEPROP 2 LAST SIG_NAME P3E_CPU0_PE1_PCH_CON_TXP<15:8>
J 0
(-5635 1360);
DISPLAY 1.021277 (-5635 1360);
PAINT ORANGE (-5635 1360);
WIRE 17 -1 (-5300 1425)(-5500 1425);
WIRE 17 -1 (-5100 1425)(-5300 1425);
WIRE 17 -1 (-5750 2325)(-5950 2325);
WIRE 17 -1 (-5550 2325)(-5750 2325);
WIRE 17 -1 (-5950 2325)(-6050 2325);
FORCEPROP 2 LAST SIG_NAME P3E_CPU0_PE1_PCH_TXP<15:8>
J 0
(-6010 2360);
DISPLAY 1.021277 (-6010 2360);
PAINT ORANGE (-6010 2360);
WIRE 17 -1 (-5350 2325)(-5550 2325);
WIRE 17 -1 (-5800 2725)(-6000 2725);
WIRE 17 -1 (-5600 2725)(-5800 2725);
FORCEPROP 2 LAST SIG_NAME P3E_CPU0_PE1_PCH_CON_TXN<15:8>
J 0
(-5710 2660);
DISPLAY 1.021277 (-5710 2660);
PAINT ORANGE (-5710 2660);
WIRE 17 -1 (-5400 2725)(-5600 2725);
WIRE 17 -1 (-5200 2725)(-5400 2725);
WIRE 17 -1 (-5000 2725)(-5200 2725);
WIRE 17 -1 (-5850 3625)(-6050 3625);
WIRE 17 -1 (-5650 3625)(-5850 3625);
WIRE 17 -1 (-6050 3625)(-6150 3625);
FORCEPROP 2 LAST SIG_NAME P3E_CPU0_PE1_PCH_TXN<15:8>
J 0
(-6085 3660);
DISPLAY 1.021277 (-6085 3660);
PAINT ORANGE (-6085 3660);
WIRE 17 -1 (-5450 3625)(-5650 3625);
WIRE 17 -1 (-5250 3625)(-5450 3625);
WIRE 17 -1 (-5050 3625)(-5250 3625);
WIRE 17 -1 (-4850 3625)(-5050 3625);
WIRE 17 -1 (-4850 3625)(-4650 3625);
WIRE 17 -1 (-4700 1425)(-4900 1425);
WIRE 17 -1 (-4500 1425)(-4700 1425);
WIRE 17 -1 (-4900 1425)(-5100 1425);
WIRE 17 -1 (-4275 1425)(-4500 1425);
WIRE 17 -1 (-3200 1425)(-3400 1425);
WIRE 17 -1 (-3000 1425)(-3200 1425);
FORCEPROP 2 LAST SIG_NAME P3E_CPU0_PE1_PCH_CON_RXP<15:8>
J 0
(-3085 1335);
DISPLAY 1.021277 (-3085 1335);
PAINT ORANGE (-3085 1335);
WIRE 17 -1 (-4750 2325)(-4950 2325);
WIRE 17 -1 (-4750 2325)(-4550 2325);
WIRE 17 -1 (-4950 2325)(-5150 2325);
WIRE 17 -1 (-5150 2325)(-5350 2325);
WIRE 17 -1 (-4800 2725)(-5000 2725);
WIRE 17 -1 (-4600 2725)(-4800 2725);
WIRE 17 -1 (-4375 2725)(-4600 2725);
WIRE 17 -1 (-3275 2725)(-3475 2725);
WIRE 17 -1 (-3075 2725)(-3275 2725);
FORCEPROP 2 LAST SIG_NAME P3E_CPU0_PE1_PCH_CON_RXN<15:8>
J 0
(-3185 2660);
DISPLAY 1.021277 (-3185 2660);
PAINT ORANGE (-3185 2660);
WIRE 17 -1 (-2925 3625)(-3125 3625);
WIRE 17 -1 (-2725 3625)(-2925 3625);
WIRE 17 -1 (-3125 3625)(-3325 3625);
WIRE 17 -1 (-3325 3625)(-3525 3625);
WIRE 17 -1 (-2525 3625)(-2725 3625);
WIRE 17 -1 (-2325 3625)(-2525 3625);
WIRE 17 -1 (-3525 3625)(-3625 3625);
FORCEPROP 2 LAST SIG_NAME P3E_CPU0_PE1_PCH_RXN<15:8>
J 0
(-3610 3660);
DISPLAY 1.021277 (-3610 3660);
PAINT ORANGE (-3610 3660);
WIRE 17 -1 (-2600 1425)(-2800 1425);
WIRE 17 -1 (-2400 1425)(-2600 1425);
WIRE 17 -1 (-2800 1425)(-3000 1425);
WIRE 17 -1 (-2200 1425)(-2400 1425);
WIRE 17 -1 (-2000 1425)(-2200 1425);
WIRE 17 -1 (-1775 1425)(-2000 1425);
WIRE 17 -1 (-2450 2325)(-2650 2325);
WIRE 17 -1 (-2250 2325)(-2450 2325);
WIRE 17 -1 (-2650 2325)(-2850 2325);
WIRE 17 -1 (-2850 2325)(-3050 2325);
WIRE 17 -1 (-2250 2325)(-2050 2325);
WIRE 17 -1 (-3050 2325)(-3250 2325);
WIRE 17 -1 (-3250 2325)(-3450 2325);
WIRE 17 -1 (-3450 2325)(-3550 2325);
FORCEPROP 2 LAST SIG_NAME P3E_CPU0_PE1_PCH_RXP<15:8>
J 0
(-3510 2360);
DISPLAY 1.021277 (-3510 2360);
PAINT ORANGE (-3510 2360);
WIRE 17 -1 (-2875 2725)(-3075 2725);
WIRE 17 -1 (-2675 2725)(-2875 2725);
WIRE 17 -1 (-2475 2725)(-2675 2725);
WIRE 17 -1 (-2275 2725)(-2475 2725);
WIRE 17 -1 (-2075 2725)(-2275 2725);
WIRE 17 -1 (-1850 2725)(-2075 2725);
WIRE 17 -1 (-2325 3625)(-2125 3625);
WIRE 3 2175 (-7475 4400)(-800 4400);
WIRE 3 2175 (-7475 4400)(-7475 650);
WIRE 3 2175 (-800 4400)(-800 650);
WIRE 3 2175 (-7475 650)(-800 650);
WIRE 16 -1 (-3425 2225)(-3425 1825);
WIRE 16 -1 (-3225 2225)(-3225 2125);
WIRE 16 -1 (-3025 2225)(-3025 1825);
WIRE 16 -1 (-2100 2825)(-2100 3225);
WIRE 16 -1 (-3225 1925)(-3225 1525);
WIRE 16 -1 (-2825 1525)(-2825 1925);
WIRE 16 -1 (-2425 1525)(-2425 1925);
WIRE 16 -1 (-5125 1525)(-5125 1625);
WIRE 16 -1 (-6025 3525)(-6025 3125);
WIRE 16 -1 (-5825 3225)(-5825 2825);
WIRE 16 -1 (-5525 2225)(-5525 1825);
WIRE 16 -1 (-4925 1525)(-4925 1925);
WIRE 16 -1 (-5125 2225)(-5125 1825);
WIRE 16 -1 (-5325 2225)(-5325 2125);
WIRE 16 -1 (-3500 3525)(-3500 3125);
WIRE 16 -1 (-2025 2125)(-2025 2225);
WIRE 16 -1 (-2100 3425)(-2100 3525);
WIRE 16 -1 (-2500 3425)(-2500 3525);
WIRE 16 -1 (-2300 3125)(-2300 3525);
WIRE 16 -1 (-2900 3525)(-2900 3425);
WIRE 16 -1 (-2700 3525)(-2700 3125);
WIRE 16 -1 (-2300 2825)(-2300 2925);
WIRE 16 -1 (-2500 2825)(-2500 3225);
WIRE 16 -1 (-2700 2825)(-2700 2925);
WIRE 16 -1 (-2900 2825)(-2900 3225);
WIRE 16 -1 (-2425 2125)(-2425 2225);
WIRE 16 -1 (-2825 2225)(-2825 2125);
WIRE 16 -1 (-2025 1525)(-2025 1925);
WIRE 16 -1 (-2225 1825)(-2225 2225);
WIRE 16 -1 (-2625 2225)(-2625 1825);
WIRE 16 -1 (-2225 1525)(-2225 1625);
WIRE 16 -1 (-2625 1525)(-2625 1625);
WIRE 16 -1 (-3025 1525)(-3025 1625);
WIRE 16 -1 (-3300 3525)(-3300 3425);
WIRE 16 -1 (-3100 3525)(-3100 3125);
WIRE 16 -1 (-3300 3225)(-3300 2825);
WIRE 16 -1 (-3100 2825)(-3100 2925);
WIRE 16 -1 (-3500 2825)(-3500 2925);
WIRE 16 -1 (-5025 3425)(-5025 3525);
WIRE 16 -1 (-4625 3400)(-4625 3525);
WIRE 16 -1 (-4825 3125)(-4825 3525);
WIRE 16 -1 (-4625 2825)(-4625 3200);
WIRE 16 -1 (-5025 2825)(-5025 3225);
WIRE 16 -1 (-4825 2825)(-4825 2925);
WIRE 16 -1 (-4525 2125)(-4525 2225);
WIRE 16 -1 (-4925 2125)(-4925 2225);
WIRE 16 -1 (-4725 1825)(-4725 2225);
WIRE 16 -1 (-4525 1525)(-4525 1925);
WIRE 16 -1 (-3425 1525)(-3425 1625);
WIRE 16 -1 (-4725 1525)(-4725 1625);
WIRE 16 -1 (-5425 3525)(-5425 3425);
WIRE 16 -1 (-5225 3525)(-5225 3125);
WIRE 16 -1 (-5625 3525)(-5625 3125);
WIRE 16 -1 (-5825 3525)(-5825 3425);
WIRE 16 -1 (-5225 2825)(-5225 2925);
WIRE 16 -1 (-5625 2825)(-5625 2925);
WIRE 16 -1 (-5425 2825)(-5425 3225);
WIRE 16 -1 (-6025 2825)(-6025 2925);
WIRE 16 -1 (-5725 2225)(-5725 2125);
WIRE 16 -1 (-5925 2225)(-5925 1825);
WIRE 16 -1 (-5325 1525)(-5325 1925);
WIRE 16 -1 (-5725 1925)(-5725 1525);
WIRE 16 -1 (-5525 1525)(-5525 1625);
WIRE 16 -1 (-5925 1525)(-5925 1625);
FORCENOTE
TP FAB1 ADD PE1[8:15] PATH TO X24 CONNECTOR
(-4675 925) 0;
DISPLAY LEFT (-4675 925);
DISPLAY 1.702128 (-4675 925);
PAINT RED (-4675 925);
QUIT
